G04 ================== begin FILE IDENTIFICATION RECORD ==================*
G04 Layout Name:  D:/<user>/Wistron_project/16315-1/gbr/16315-1.brd*
G04 Film Name:    DP_REF_L3*
G04 File Format:  Gerber RS274X*
G04 File Origin:  Cadence Allegro 16.5-S056*
G04 Origin Date:  Fri Jun 09 15:32:34 2017*
G04 *
G04 Layer:  BOARD GEOMETRY/DP_REF_L3_TBL*
G04 Layer:  BOARD GEOMETRY/DP_REF_L3_L3*
G04 Layer:  BOARD GEOMETRY/PANEL_OUTLINE*
G04 *
G04 Offset:    (0.00 0.00)*
G04 Mirror:    No*
G04 Mode:      Positive*
G04 Rotation:  0*
G04 FullContactRelief:  No*
G04 UndefLineWidth:     6.00*
G04 ================== end FILE IDENTIFICATION RECORD ====================*
%FSLAX35Y35*MOIN*%
%IR0*IPPOS*OFA0.00000B0.00000*MIA0B0*SFA1.00000B1.00000*%
%ADD10C,.02*%
%ADD11C,.006*%
%ADD12C,.0055*%
G75*
%LPD*%
G75*
G54D10*
G01X1985143Y1554618D02*
X2807643D01*
G01X1985143Y1519968D02*
X2807643D01*
G01X1985143Y1623918D02*
Y1519968D01*
G01Y1589268D02*
X2807643D01*
G01X1985143Y1623918D02*
X2807643D01*
G01X2160143D02*
Y1519968D01*
G01X2492643Y1623918D02*
Y1519968D01*
G01X2597643Y1623918D02*
Y1519968D01*
G01X2807643Y1623918D02*
Y1519968D01*
G54D11*
G01X6250Y-185556D02*
Y-203056D01*
G01X1228Y-185556D02*
X11272D01*
G01X20038Y-203056D02*
Y-185556D01*
G01Y-194014D02*
X21130Y-192556D01*
X22222Y-191681D01*
X23968Y-191390D01*
X25278Y-191681D01*
X26807Y-192848D01*
X27462Y-194598D01*
Y-203056D01*
G01X41250Y-191390D02*
Y-203056D01*
G01Y-186723D02*
X40813Y-186431D01*
Y-185848D01*
X41250Y-185556D01*
X41687Y-185848D01*
Y-186431D01*
X41250Y-186723D01*
G01X55475Y-201015D02*
X56567Y-202181D01*
X58095Y-203056D01*
X59405D01*
X60715Y-202473D01*
X61588Y-201598D01*
X62025Y-200432D01*
X61807Y-198681D01*
X60933Y-197806D01*
X57003Y-196056D01*
X56130Y-194014D01*
X56567Y-192556D01*
X57440Y-191681D01*
X58750Y-191390D01*
X60060Y-191681D01*
X61370Y-192556D01*
G01X90693Y-207431D02*
X92222Y-208598D01*
X93968Y-208889D01*
X95496Y-208598D01*
X96807Y-207140D01*
X97680Y-205098D01*
Y-191390D01*
G01Y-193723D02*
X96807Y-192556D01*
X95496Y-191681D01*
X93968Y-191390D01*
X92222Y-191973D01*
X91130Y-193139D01*
X90256Y-195181D01*
X89820Y-197223D01*
X90038Y-198973D01*
X90912Y-201015D01*
X92222Y-202473D01*
X93968Y-203056D01*
X95278Y-202764D01*
X96807Y-201598D01*
X97680Y-200432D01*
G01X107975Y-195181D02*
X114962D01*
X114307Y-193139D01*
X113215Y-191973D01*
X111687Y-191390D01*
X110158Y-191681D01*
X108848Y-192556D01*
X107975Y-194598D01*
X107538Y-196348D01*
Y-198098D01*
X107975Y-199848D01*
X109067Y-201598D01*
X110377Y-202764D01*
X111905Y-203056D01*
X113433Y-202473D01*
X114962Y-200723D01*
G01X125693Y-203056D02*
Y-191390D01*
G01Y-193723D02*
X126785Y-192556D01*
X127877Y-191681D01*
X129405Y-191390D01*
X130496Y-191681D01*
X131807Y-192556D01*
G01X142320Y-203056D02*
Y-185556D01*
G01Y-194306D02*
X143412Y-192556D01*
X144722Y-191681D01*
X146032Y-191390D01*
X147996Y-191973D01*
X149307Y-193139D01*
X150180Y-195181D01*
Y-197514D01*
X149743Y-199848D01*
X148870Y-201598D01*
X147342Y-202764D01*
X146032Y-203056D01*
X144722Y-202764D01*
X143412Y-201890D01*
X142320Y-200432D01*
G01X160475Y-195181D02*
X167462D01*
X166807Y-193139D01*
X165715Y-191973D01*
X164187Y-191390D01*
X162658Y-191681D01*
X161348Y-192556D01*
X160475Y-194598D01*
X160038Y-196348D01*
Y-198098D01*
X160475Y-199848D01*
X161567Y-201598D01*
X162877Y-202764D01*
X164405Y-203056D01*
X165933Y-202473D01*
X167462Y-200723D01*
G01X178193Y-203056D02*
Y-191390D01*
G01Y-193723D02*
X179285Y-192556D01*
X180377Y-191681D01*
X181905Y-191390D01*
X182996Y-191681D01*
X184307Y-192556D01*
G01X216250Y-191390D02*
Y-203056D01*
G01Y-186723D02*
X215813Y-186431D01*
Y-185848D01*
X216250Y-185556D01*
X216687Y-185848D01*
Y-186431D01*
X216250Y-186723D01*
G01X230475Y-201015D02*
X231567Y-202181D01*
X233095Y-203056D01*
X234405D01*
X235715Y-202473D01*
X236588Y-201598D01*
X237025Y-200432D01*
X236807Y-198681D01*
X235933Y-197806D01*
X232003Y-196056D01*
X231130Y-194014D01*
X231567Y-192556D01*
X232440Y-191681D01*
X233750Y-191390D01*
X235060Y-191681D01*
X236370Y-192556D01*
G01X265256Y-207431D02*
X266785Y-208598D01*
X268095Y-208889D01*
X269842Y-208306D01*
X271152Y-206848D01*
X271807Y-204222D01*
Y-191390D01*
G01Y-186723D02*
X271370Y-186431D01*
Y-185848D01*
X271807Y-185556D01*
X272243Y-185848D01*
Y-186431D01*
X271807Y-186723D01*
G01X282538Y-191390D02*
Y-199556D01*
X283412Y-201598D01*
X284722Y-202764D01*
X286250Y-203056D01*
X287778Y-202764D01*
X289088Y-201598D01*
X289962Y-199556D01*
G01Y-203056D02*
Y-191390D01*
G01X300475Y-201015D02*
X301567Y-202181D01*
X303095Y-203056D01*
X304405D01*
X305715Y-202473D01*
X306588Y-201598D01*
X307025Y-200432D01*
X306807Y-198681D01*
X305933Y-197806D01*
X302003Y-196056D01*
X301130Y-194014D01*
X301567Y-192556D01*
X302440Y-191681D01*
X303750Y-191390D01*
X305060Y-191681D01*
X306370Y-192556D01*
G01X321250Y-185556D02*
Y-203056D01*
G01X318193Y-191390D02*
X324307D01*
G01X354940Y-203056D02*
Y-188181D01*
X355377Y-186723D01*
X356250Y-185848D01*
X357560Y-185556D01*
X358870Y-186139D01*
X359525Y-187598D01*
G01X356905Y-192556D02*
X352538D01*
G01X373750Y-203056D02*
X372440Y-202764D01*
X371130Y-201598D01*
X370256Y-199556D01*
X369820Y-197223D01*
X370256Y-194889D01*
X371130Y-192848D01*
X372440Y-191681D01*
X373750Y-191390D01*
X375060Y-191681D01*
X376370Y-192848D01*
X377243Y-194889D01*
X377462Y-197223D01*
X377243Y-199556D01*
X376370Y-201598D01*
X375060Y-202764D01*
X373750Y-203056D01*
G01X388193D02*
Y-191390D01*
G01Y-193723D02*
X389285Y-192556D01*
X390377Y-191681D01*
X391905Y-191390D01*
X392996Y-191681D01*
X394307Y-192556D01*
G01X421665Y-208306D02*
X422975Y-208889D01*
X424722Y-208306D01*
X425813Y-207140D01*
X426687Y-205681D01*
X427996Y-201015D01*
X430835Y-191390D01*
G01X423848D02*
X427996Y-201015D01*
G01X443750Y-203056D02*
X442440Y-202764D01*
X441130Y-201598D01*
X440256Y-199556D01*
X439820Y-197223D01*
X440256Y-194889D01*
X441130Y-192848D01*
X442440Y-191681D01*
X443750Y-191390D01*
X445060Y-191681D01*
X446370Y-192848D01*
X447243Y-194889D01*
X447462Y-197223D01*
X447243Y-199556D01*
X446370Y-201598D01*
X445060Y-202764D01*
X443750Y-203056D01*
G01X457538Y-191390D02*
Y-199556D01*
X458412Y-201598D01*
X459722Y-202764D01*
X461250Y-203056D01*
X462778Y-202764D01*
X464088Y-201598D01*
X464962Y-199556D01*
G01Y-203056D02*
Y-191390D01*
G01X475693Y-203056D02*
Y-191390D01*
G01Y-193723D02*
X476785Y-192556D01*
X477877Y-191681D01*
X479405Y-191390D01*
X480496Y-191681D01*
X481807Y-192556D01*
G01X510693Y-203056D02*
Y-191390D01*
G01Y-193723D02*
X511785Y-192556D01*
X512877Y-191681D01*
X514405Y-191390D01*
X515496Y-191681D01*
X516807Y-192556D01*
G01X527975Y-195181D02*
X534962D01*
X534307Y-193139D01*
X533215Y-191973D01*
X531687Y-191390D01*
X530158Y-191681D01*
X528848Y-192556D01*
X527975Y-194598D01*
X527538Y-196348D01*
Y-198098D01*
X527975Y-199848D01*
X529067Y-201598D01*
X530377Y-202764D01*
X531905Y-203056D01*
X533433Y-202473D01*
X534962Y-200723D01*
G01X547440Y-203056D02*
Y-188181D01*
X547877Y-186723D01*
X548750Y-185848D01*
X550060Y-185556D01*
X551370Y-186139D01*
X552025Y-187598D01*
G01X549405Y-192556D02*
X545038D01*
G01X562975Y-195181D02*
X569962D01*
X569307Y-193139D01*
X568215Y-191973D01*
X566687Y-191390D01*
X565158Y-191681D01*
X563848Y-192556D01*
X562975Y-194598D01*
X562538Y-196348D01*
Y-198098D01*
X562975Y-199848D01*
X564067Y-201598D01*
X565377Y-202764D01*
X566905Y-203056D01*
X568433Y-202473D01*
X569962Y-200723D01*
G01X580693Y-203056D02*
Y-191390D01*
G01Y-193723D02*
X581785Y-192556D01*
X582877Y-191681D01*
X584405Y-191390D01*
X585496Y-191681D01*
X586807Y-192556D01*
G01X597975Y-195181D02*
X604962D01*
X604307Y-193139D01*
X603215Y-191973D01*
X601687Y-191390D01*
X600158Y-191681D01*
X598848Y-192556D01*
X597975Y-194598D01*
X597538Y-196348D01*
Y-198098D01*
X597975Y-199848D01*
X599067Y-201598D01*
X600377Y-202764D01*
X601905Y-203056D01*
X603433Y-202473D01*
X604962Y-200723D01*
G01X615038Y-203056D02*
Y-191390D01*
G01Y-194306D02*
X615912Y-192848D01*
X617222Y-191681D01*
X618968Y-191390D01*
X620496Y-191681D01*
X621807Y-192848D01*
X622462Y-194889D01*
Y-203056D01*
G01X639743Y-192848D02*
X638215Y-191681D01*
X636905Y-191390D01*
X635158Y-191973D01*
X633848Y-193139D01*
X632975Y-195181D01*
X632756Y-197223D01*
X632975Y-199265D01*
X633848Y-201015D01*
X635158Y-202473D01*
X636905Y-203056D01*
X638433Y-202473D01*
X639743Y-201306D01*
G01X650475Y-195181D02*
X657462D01*
X656807Y-193139D01*
X655715Y-191973D01*
X654187Y-191390D01*
X652658Y-191681D01*
X651348Y-192556D01*
X650475Y-194598D01*
X650038Y-196348D01*
Y-198098D01*
X650475Y-199848D01*
X651567Y-201598D01*
X652877Y-202764D01*
X654405Y-203056D01*
X655933Y-202473D01*
X657462Y-200723D01*
G01X688750Y-185556D02*
Y-203056D01*
G01X685693Y-191390D02*
X691807D01*
G01X706250Y-203056D02*
X704940Y-202764D01*
X703630Y-201598D01*
X702756Y-199556D01*
X702320Y-197223D01*
X702756Y-194889D01*
X703630Y-192848D01*
X704940Y-191681D01*
X706250Y-191390D01*
X707560Y-191681D01*
X708870Y-192848D01*
X709743Y-194889D01*
X709962Y-197223D01*
X709743Y-199556D01*
X708870Y-201598D01*
X707560Y-202764D01*
X706250Y-203056D01*
G01X739940D02*
Y-188181D01*
X740377Y-186723D01*
X741250Y-185848D01*
X742560Y-185556D01*
X743870Y-186139D01*
X744525Y-187598D01*
G01X741905Y-192556D02*
X737538D01*
G01X758750Y-191390D02*
Y-203056D01*
G01Y-186723D02*
X758313Y-186431D01*
Y-185848D01*
X758750Y-185556D01*
X759187Y-185848D01*
Y-186431D01*
X758750Y-186723D01*
G01X772538Y-203056D02*
Y-191390D01*
G01Y-194306D02*
X773412Y-192848D01*
X774722Y-191681D01*
X776468Y-191390D01*
X777996Y-191681D01*
X779307Y-192848D01*
X779962Y-194889D01*
Y-203056D01*
G01X797680Y-185556D02*
Y-203056D01*
G01Y-200432D02*
X796807Y-201890D01*
X795496Y-202764D01*
X793968Y-203056D01*
X792222Y-202473D01*
X790912Y-201015D01*
X790038Y-199265D01*
X789820Y-197223D01*
X790038Y-195181D01*
X790912Y-193431D01*
X792222Y-191973D01*
X793968Y-191390D01*
X795496Y-191681D01*
X796588Y-192265D01*
X797680Y-193431D01*
G01X828750Y-185556D02*
Y-203056D01*
G01X825693Y-191390D02*
X831807D01*
G01X842538Y-203056D02*
Y-185556D01*
G01Y-194014D02*
X843630Y-192556D01*
X844722Y-191681D01*
X846468Y-191390D01*
X847778Y-191681D01*
X849307Y-192848D01*
X849962Y-194598D01*
Y-203056D01*
G01X860475Y-195181D02*
X867462D01*
X866807Y-193139D01*
X865715Y-191973D01*
X864187Y-191390D01*
X862658Y-191681D01*
X861348Y-192556D01*
X860475Y-194598D01*
X860038Y-196348D01*
Y-198098D01*
X860475Y-199848D01*
X861567Y-201598D01*
X862877Y-202764D01*
X864405Y-203056D01*
X865933Y-202473D01*
X867462Y-200723D01*
G01X893947Y-203056D02*
Y-185556D01*
X898313D01*
X900060Y-186431D01*
X901370Y-187598D01*
X902462Y-189347D01*
X903335Y-191390D01*
X903553Y-194306D01*
X903335Y-197223D01*
X902462Y-199265D01*
X901370Y-201015D01*
X900060Y-202181D01*
X898313Y-203056D01*
X893947D01*
G01X911883D02*
Y-185556D01*
X917123D01*
X918870Y-186431D01*
X920180Y-188473D01*
X920617Y-190806D01*
X920180Y-193139D01*
X919088Y-194889D01*
X917123Y-195765D01*
X911883D01*
G01X951250Y-191390D02*
Y-203056D01*
G01Y-186723D02*
X950813Y-186431D01*
Y-185848D01*
X951250Y-185556D01*
X951687Y-185848D01*
Y-186431D01*
X951250Y-186723D01*
G01X962200Y-203056D02*
Y-191390D01*
G01Y-194598D02*
X962855Y-193139D01*
X963947Y-191973D01*
X965475Y-191390D01*
X967003Y-191973D01*
X968095Y-193139D01*
X968750Y-194598D01*
Y-203056D01*
G01Y-194598D02*
X969405Y-193139D01*
X970496Y-191973D01*
X972025Y-191390D01*
X973553Y-191973D01*
X974645Y-193139D01*
X975300Y-194889D01*
Y-203056D01*
G01X982320Y-208889D02*
Y-191390D01*
G01Y-194014D02*
X983412Y-192556D01*
X984503Y-191681D01*
X986250Y-191390D01*
X987778Y-191681D01*
X989307Y-193139D01*
X989962Y-195181D01*
X990180Y-197223D01*
X989962Y-199265D01*
X989307Y-201306D01*
X987996Y-202473D01*
X986250Y-203056D01*
X984722Y-202764D01*
X983193Y-201890D01*
X982320Y-200723D01*
G01X1000475Y-195181D02*
X1007462D01*
X1006807Y-193139D01*
X1005715Y-191973D01*
X1004187Y-191390D01*
X1002658Y-191681D01*
X1001348Y-192556D01*
X1000475Y-194598D01*
X1000038Y-196348D01*
Y-198098D01*
X1000475Y-199848D01*
X1001567Y-201598D01*
X1002877Y-202764D01*
X1004405Y-203056D01*
X1005933Y-202473D01*
X1007462Y-200723D01*
G01X1025180Y-185556D02*
Y-203056D01*
G01Y-200432D02*
X1024307Y-201890D01*
X1022996Y-202764D01*
X1021468Y-203056D01*
X1019722Y-202473D01*
X1018412Y-201015D01*
X1017538Y-199265D01*
X1017320Y-197223D01*
X1017538Y-195181D01*
X1018412Y-193431D01*
X1019722Y-191973D01*
X1021468Y-191390D01*
X1022996Y-191681D01*
X1024088Y-192265D01*
X1025180Y-193431D01*
G01X1042680Y-203056D02*
Y-191390D01*
G01Y-193431D02*
X1041807Y-192265D01*
X1040496Y-191681D01*
X1038968Y-191390D01*
X1037440Y-191973D01*
X1036130Y-193139D01*
X1035256Y-194889D01*
X1034820Y-197223D01*
X1035256Y-199556D01*
X1036130Y-201306D01*
X1037440Y-202473D01*
X1038968Y-203056D01*
X1040496Y-202764D01*
X1041807Y-201890D01*
X1042680Y-200723D01*
G01X1052538Y-203056D02*
Y-191390D01*
G01Y-194306D02*
X1053412Y-192848D01*
X1054722Y-191681D01*
X1056468Y-191390D01*
X1057996Y-191681D01*
X1059307Y-192848D01*
X1059962Y-194889D01*
Y-203056D01*
G01X1077243Y-192848D02*
X1075715Y-191681D01*
X1074405Y-191390D01*
X1072658Y-191973D01*
X1071348Y-193139D01*
X1070475Y-195181D01*
X1070256Y-197223D01*
X1070475Y-199265D01*
X1071348Y-201015D01*
X1072658Y-202473D01*
X1074405Y-203056D01*
X1075933Y-202473D01*
X1077243Y-201306D01*
G01X1087975Y-195181D02*
X1094962D01*
X1094307Y-193139D01*
X1093215Y-191973D01*
X1091687Y-191390D01*
X1090158Y-191681D01*
X1088848Y-192556D01*
X1087975Y-194598D01*
X1087538Y-196348D01*
Y-198098D01*
X1087975Y-199848D01*
X1089067Y-201598D01*
X1090377Y-202764D01*
X1091905Y-203056D01*
X1093433Y-202473D01*
X1094962Y-200723D01*
G01X1126250Y-185556D02*
Y-203056D01*
G01X1123193Y-191390D02*
X1129307D01*
G01X1140693Y-203056D02*
Y-191390D01*
G01Y-193723D02*
X1141785Y-192556D01*
X1142877Y-191681D01*
X1144405Y-191390D01*
X1145496Y-191681D01*
X1146807Y-192556D01*
G01X1165180Y-203056D02*
Y-191390D01*
G01Y-193431D02*
X1164307Y-192265D01*
X1162996Y-191681D01*
X1161468Y-191390D01*
X1159940Y-191973D01*
X1158630Y-193139D01*
X1157756Y-194889D01*
X1157320Y-197223D01*
X1157756Y-199556D01*
X1158630Y-201306D01*
X1159940Y-202473D01*
X1161468Y-203056D01*
X1162996Y-202764D01*
X1164307Y-201890D01*
X1165180Y-200723D01*
G01X1182243Y-192848D02*
X1180715Y-191681D01*
X1179405Y-191390D01*
X1177658Y-191973D01*
X1176348Y-193139D01*
X1175475Y-195181D01*
X1175256Y-197223D01*
X1175475Y-199265D01*
X1176348Y-201015D01*
X1177658Y-202473D01*
X1179405Y-203056D01*
X1180933Y-202473D01*
X1182243Y-201306D01*
G01X1192975Y-195181D02*
X1199962D01*
X1199307Y-193139D01*
X1198215Y-191973D01*
X1196687Y-191390D01*
X1195158Y-191681D01*
X1193848Y-192556D01*
X1192975Y-194598D01*
X1192538Y-196348D01*
Y-198098D01*
X1192975Y-199848D01*
X1194067Y-201598D01*
X1195377Y-202764D01*
X1196905Y-203056D01*
X1198433Y-202473D01*
X1199962Y-200723D01*
G01X1210475Y-201015D02*
X1211567Y-202181D01*
X1213095Y-203056D01*
X1214405D01*
X1215715Y-202473D01*
X1216588Y-201598D01*
X1217025Y-200432D01*
X1216807Y-198681D01*
X1215933Y-197806D01*
X1212003Y-196056D01*
X1211130Y-194014D01*
X1211567Y-192556D01*
X1212440Y-191681D01*
X1213750Y-191390D01*
X1215060Y-191681D01*
X1216370Y-192556D01*
G01X1248750Y-191390D02*
Y-203056D01*
G01Y-186723D02*
X1248313Y-186431D01*
Y-185848D01*
X1248750Y-185556D01*
X1249187Y-185848D01*
Y-186431D01*
X1248750Y-186723D01*
G01X1262538Y-203056D02*
Y-191390D01*
G01Y-194306D02*
X1263412Y-192848D01*
X1264722Y-191681D01*
X1266468Y-191390D01*
X1267996Y-191681D01*
X1269307Y-192848D01*
X1269962Y-194889D01*
Y-203056D01*
G01X1301250D02*
Y-185556D01*
G01X1322680Y-203056D02*
Y-191390D01*
G01Y-193431D02*
X1321807Y-192265D01*
X1320496Y-191681D01*
X1318968Y-191390D01*
X1317440Y-191973D01*
X1316130Y-193139D01*
X1315256Y-194889D01*
X1314820Y-197223D01*
X1315256Y-199556D01*
X1316130Y-201306D01*
X1317440Y-202473D01*
X1318968Y-203056D01*
X1320496Y-202764D01*
X1321807Y-201890D01*
X1322680Y-200723D01*
G01X1331665Y-208306D02*
X1332975Y-208889D01*
X1334722Y-208306D01*
X1335813Y-207140D01*
X1336687Y-205681D01*
X1337996Y-201015D01*
X1340835Y-191390D01*
G01X1333848D02*
X1337996Y-201015D01*
G01X1350475Y-195181D02*
X1357462D01*
X1356807Y-193139D01*
X1355715Y-191973D01*
X1354187Y-191390D01*
X1352658Y-191681D01*
X1351348Y-192556D01*
X1350475Y-194598D01*
X1350038Y-196348D01*
Y-198098D01*
X1350475Y-199848D01*
X1351567Y-201598D01*
X1352877Y-202764D01*
X1354405Y-203056D01*
X1355933Y-202473D01*
X1357462Y-200723D01*
G01X1368193Y-203056D02*
Y-191390D01*
G01Y-193723D02*
X1369285Y-192556D01*
X1370377Y-191681D01*
X1371905Y-191390D01*
X1372996Y-191681D01*
X1374307Y-192556D01*
G01X1401883Y-185556D02*
Y-203056D01*
X1410617D01*
G01X1418947Y-199556D02*
X1420256Y-201598D01*
X1422003Y-202764D01*
X1423968Y-203056D01*
X1425715Y-202764D01*
X1427462Y-201306D01*
X1428553Y-199556D01*
X1428772Y-197806D01*
X1428335Y-195765D01*
X1426807Y-194306D01*
X1425278Y-193723D01*
X1423313D01*
G01X1425278D02*
X1426588Y-192848D01*
X1427680Y-191390D01*
X1428117Y-189640D01*
X1427680Y-187889D01*
X1426588Y-186431D01*
X1424623Y-185556D01*
X1422658Y-185848D01*
X1420693Y-187015D01*
G01X1441250Y-203639D02*
X1440813Y-203348D01*
Y-202764D01*
X1441250Y-202473D01*
X1441687Y-202764D01*
Y-203348D01*
X1441250Y-203639D01*
G01X2008773Y1616518D02*
X2014013D01*
G01X2011393D02*
Y1599018D01*
G01X2008773D02*
X2014013D01*
G01X2023216D02*
Y1616518D01*
X2028893Y1601935D01*
X2034570Y1616518D01*
Y1599018D01*
G01X2042026D02*
Y1616518D01*
X2047266D01*
X2049013Y1615643D01*
X2050323Y1613601D01*
X2050760Y1611268D01*
X2050323Y1608935D01*
X2049231Y1607185D01*
X2047266Y1606309D01*
X2042026D01*
G01X2062801Y1593185D02*
X2060618Y1596101D01*
X2059526Y1599018D01*
Y1610684D01*
X2060618Y1613601D01*
X2062801Y1616518D01*
G01X2081393Y1599018D02*
X2079646Y1599310D01*
X2078118Y1600476D01*
X2076808Y1602226D01*
X2075934Y1604268D01*
X2075498Y1606601D01*
Y1608935D01*
X2075934Y1611268D01*
X2076808Y1613310D01*
X2078118Y1615059D01*
X2079646Y1616226D01*
X2081393Y1616518D01*
X2083139Y1616226D01*
X2084668Y1615059D01*
X2085978Y1613310D01*
X2086852Y1611268D01*
X2087288Y1608935D01*
Y1606601D01*
X2086852Y1604268D01*
X2085978Y1602226D01*
X2084668Y1600476D01*
X2083139Y1599310D01*
X2081393Y1599018D01*
G01X2095181D02*
Y1616518D01*
G01Y1608060D02*
X2096273Y1609518D01*
X2097365Y1610393D01*
X2099111Y1610684D01*
X2100421Y1610393D01*
X2101950Y1609226D01*
X2102605Y1607476D01*
Y1599018D01*
G01X2109843D02*
Y1610684D01*
G01Y1607476D02*
X2110498Y1608935D01*
X2111590Y1610101D01*
X2113118Y1610684D01*
X2114646Y1610101D01*
X2115738Y1608935D01*
X2116393Y1607476D01*
Y1599018D01*
G01Y1607476D02*
X2117048Y1608935D01*
X2118139Y1610101D01*
X2119668Y1610684D01*
X2121196Y1610101D01*
X2122288Y1608935D01*
X2122943Y1607185D01*
Y1599018D01*
G01X2134985Y1593185D02*
X2137168Y1596101D01*
X2138260Y1599018D01*
Y1610684D01*
X2137168Y1613601D01*
X2134985Y1616518D01*
G01X1986890Y1633668D02*
Y1651168D01*
X1991256D01*
X1993003Y1650293D01*
X1994313Y1649126D01*
X1995405Y1647377D01*
X1996278Y1645334D01*
X1996496Y1642418D01*
X1996278Y1639501D01*
X1995405Y1637459D01*
X1994313Y1635709D01*
X1993003Y1634543D01*
X1991256Y1633668D01*
X1986890D01*
G01X2004826D02*
Y1651168D01*
X2010066D01*
X2011813Y1650293D01*
X2013123Y1648251D01*
X2013560Y1645918D01*
X2013123Y1643585D01*
X2012031Y1641835D01*
X2010066Y1640959D01*
X2004826D01*
G01X2041573Y1651168D02*
X2046813D01*
G01X2044193D02*
Y1633668D01*
G01X2041573D02*
X2046813D01*
G01X2056016D02*
Y1651168D01*
X2061693Y1636585D01*
X2067370Y1651168D01*
Y1633668D01*
G01X2074826D02*
Y1651168D01*
X2080066D01*
X2081813Y1650293D01*
X2083123Y1648251D01*
X2083560Y1645918D01*
X2083123Y1643585D01*
X2082031Y1641835D01*
X2080066Y1640959D01*
X2074826D01*
G01X2101060Y1633668D02*
X2092326D01*
Y1651168D01*
X2101060D01*
G01X2097566Y1642710D02*
X2092326D01*
G01X2109390Y1633668D02*
Y1651168D01*
X2113756D01*
X2115503Y1650293D01*
X2116813Y1649126D01*
X2117905Y1647377D01*
X2118778Y1645334D01*
X2118996Y1642418D01*
X2118778Y1639501D01*
X2117905Y1637459D01*
X2116813Y1635709D01*
X2115503Y1634543D01*
X2113756Y1633668D01*
X2109390D01*
G01X2126234D02*
X2131693Y1651168D01*
X2137152Y1633668D01*
G01X2135186Y1639793D02*
X2128199D01*
G01X2144171Y1633668D02*
Y1651168D01*
X2154215Y1633668D01*
Y1651168D01*
G01X2171496Y1649709D02*
X2170186Y1650585D01*
X2168658Y1651168D01*
X2166911D01*
X2164946Y1650293D01*
X2163418Y1648835D01*
X2162326Y1647084D01*
X2161453Y1644168D01*
X2161234Y1641543D01*
X2161671Y1638918D01*
X2162326Y1637168D01*
X2163636Y1635418D01*
X2165165Y1634251D01*
X2166693Y1633668D01*
X2168221D01*
X2169750Y1634251D01*
X2171060Y1635126D01*
X2172152Y1636292D01*
G01X2188560Y1633668D02*
X2179826D01*
Y1651168D01*
X2188560D01*
G01X2185066Y1642710D02*
X2179826D01*
G01X2219193Y1651168D02*
Y1633668D01*
G01X2214171Y1651168D02*
X2224215D01*
G01X2231234Y1633668D02*
X2236693Y1651168D01*
X2242152Y1633668D01*
G01X2240186Y1639793D02*
X2233199D01*
G01X2255939Y1643001D02*
X2256813Y1643876D01*
X2257468Y1645334D01*
X2257905Y1647377D01*
X2257468Y1649126D01*
X2256595Y1650293D01*
X2255066Y1651168D01*
X2249171D01*
Y1633668D01*
X2256376D01*
X2257905Y1634834D01*
X2258778Y1636585D01*
X2259215Y1638626D01*
X2258778Y1640668D01*
X2257468Y1642418D01*
X2255939Y1643001D01*
X2249171D01*
G01X2267326Y1651168D02*
Y1633668D01*
X2276060D01*
G01X2293560D02*
X2284826D01*
Y1651168D01*
X2293560D01*
G01X2290066Y1642710D02*
X2284826D01*
G01X2306693Y1633085D02*
X2306256Y1633376D01*
Y1633960D01*
X2306693Y1634251D01*
X2307130Y1633960D01*
Y1633376D01*
X2306693Y1633085D01*
G01Y1640959D02*
X2306256Y1641251D01*
Y1641835D01*
X2306693Y1642126D01*
X2307130Y1641835D01*
Y1641251D01*
X2306693Y1640959D01*
G01X2337326Y1651168D02*
Y1633668D01*
X2346060D01*
G01X2354390Y1637168D02*
X2355699Y1635126D01*
X2357446Y1633960D01*
X2359411Y1633668D01*
X2361158Y1633960D01*
X2362905Y1635418D01*
X2363996Y1637168D01*
X2364215Y1638918D01*
X2363778Y1640959D01*
X2362250Y1642418D01*
X2360721Y1643001D01*
X2358756D01*
G01X2360721D02*
X2362031Y1643876D01*
X2363123Y1645334D01*
X2363560Y1647084D01*
X2363123Y1648835D01*
X2362031Y1650293D01*
X2360066Y1651168D01*
X2358101Y1650876D01*
X2356136Y1649709D01*
G01X2046393Y1564368D02*
X2047921Y1564660D01*
X2049668Y1565534D01*
X2050760Y1566992D01*
X2051196Y1569035D01*
X2050760Y1571076D01*
X2049450Y1572826D01*
X2047485Y1573701D01*
X2045301D01*
X2043991Y1574285D01*
X2042899Y1575743D01*
X2042463Y1577784D01*
X2043118Y1579826D01*
X2044646Y1581285D01*
X2046393Y1581868D01*
X2048139Y1581285D01*
X2049668Y1579826D01*
X2050323Y1577784D01*
X2049886Y1575743D01*
X2048795Y1574285D01*
X2047485Y1573701D01*
X2045301D01*
X2043336Y1572826D01*
X2042026Y1571076D01*
X2041590Y1569035D01*
X2042026Y1566992D01*
X2043118Y1565534D01*
X2044865Y1564660D01*
X2046393Y1564368D01*
G01X2059090Y1566992D02*
X2060399Y1565534D01*
X2061928Y1564660D01*
X2063893Y1564368D01*
X2065858Y1564951D01*
X2067386Y1566118D01*
X2068478Y1568159D01*
X2068696Y1570493D01*
X2068260Y1572826D01*
X2067168Y1574285D01*
X2065639Y1575451D01*
X2064111Y1575743D01*
X2062583Y1575451D01*
X2060618Y1574285D01*
X2061273Y1581868D01*
X2067168D01*
G01X2081393Y1563785D02*
X2080956Y1564076D01*
Y1564660D01*
X2081393Y1564951D01*
X2081830Y1564660D01*
Y1564076D01*
X2081393Y1563785D01*
G01X2098893Y1581868D02*
X2097146Y1581285D01*
X2095836Y1579826D01*
X2094963Y1578077D01*
X2094308Y1575743D01*
X2094090Y1573118D01*
X2094308Y1570493D01*
X2094963Y1568159D01*
X2095836Y1566409D01*
X2097146Y1564951D01*
X2098893Y1564368D01*
X2100639Y1564951D01*
X2101950Y1566409D01*
X2102823Y1568159D01*
X2103478Y1570493D01*
X2103696Y1573118D01*
X2103478Y1575743D01*
X2102823Y1578077D01*
X2101950Y1579826D01*
X2100639Y1581285D01*
X2098893Y1581868D01*
G01X2024090Y1529135D02*
X2033696Y1541968D01*
G01X2028893Y1544301D02*
Y1526801D01*
G01X2033696Y1529135D02*
X2024090Y1541968D01*
G01X2022343Y1535551D02*
X2035443D01*
G01X2046393Y1529718D02*
Y1547218D01*
X2043773Y1543718D01*
G01Y1529718D02*
X2049013D01*
G01X2063893Y1547218D02*
X2062146Y1546635D01*
X2060836Y1545176D01*
X2059963Y1543427D01*
X2059308Y1541093D01*
X2059090Y1538468D01*
X2059308Y1535843D01*
X2059963Y1533509D01*
X2060836Y1531759D01*
X2062146Y1530301D01*
X2063893Y1529718D01*
X2065639Y1530301D01*
X2066950Y1531759D01*
X2067823Y1533509D01*
X2068478Y1535843D01*
X2068696Y1538468D01*
X2068478Y1541093D01*
X2067823Y1543427D01*
X2066950Y1545176D01*
X2065639Y1546635D01*
X2063893Y1547218D01*
G01X2081393D02*
X2079646Y1546635D01*
X2078336Y1545176D01*
X2077463Y1543427D01*
X2076808Y1541093D01*
X2076590Y1538468D01*
X2076808Y1535843D01*
X2077463Y1533509D01*
X2078336Y1531759D01*
X2079646Y1530301D01*
X2081393Y1529718D01*
X2083139Y1530301D01*
X2084450Y1531759D01*
X2085323Y1533509D01*
X2085978Y1535843D01*
X2086196Y1538468D01*
X2085978Y1541093D01*
X2085323Y1543427D01*
X2084450Y1545176D01*
X2083139Y1546635D01*
X2081393Y1547218D01*
G01X2098893Y1529135D02*
X2098456Y1529426D01*
Y1530010D01*
X2098893Y1530301D01*
X2099330Y1530010D01*
Y1529426D01*
X2098893Y1529135D01*
G01X2116393Y1547218D02*
X2114646Y1546635D01*
X2113336Y1545176D01*
X2112463Y1543427D01*
X2111808Y1541093D01*
X2111590Y1538468D01*
X2111808Y1535843D01*
X2112463Y1533509D01*
X2113336Y1531759D01*
X2114646Y1530301D01*
X2116393Y1529718D01*
X2118139Y1530301D01*
X2119450Y1531759D01*
X2120323Y1533509D01*
X2120978Y1535843D01*
X2121196Y1538468D01*
X2120978Y1541093D01*
X2120323Y1543427D01*
X2119450Y1545176D01*
X2118139Y1546635D01*
X2116393Y1547218D01*
G01X2232343Y1616518D02*
X2235399Y1599018D01*
X2238893Y1616518D01*
X2242386Y1599018D01*
X2245443Y1616518D01*
G01X2253773D02*
X2259013D01*
G01X2256393D02*
Y1599018D01*
G01X2253773D02*
X2259013D01*
G01X2269090D02*
Y1616518D01*
X2273456D01*
X2275203Y1615643D01*
X2276513Y1614476D01*
X2277605Y1612727D01*
X2278478Y1610684D01*
X2278696Y1607768D01*
X2278478Y1604851D01*
X2277605Y1602809D01*
X2276513Y1601059D01*
X2275203Y1599893D01*
X2273456Y1599018D01*
X2269090D01*
G01X2291393Y1616518D02*
Y1599018D01*
G01X2286371Y1616518D02*
X2296415D01*
G01X2304308Y1599018D02*
Y1616518D01*
G01X2313478D02*
Y1599018D01*
G01Y1607768D02*
X2304308D01*
G01X2325301Y1593185D02*
X2323118Y1596101D01*
X2322026Y1599018D01*
Y1610684D01*
X2323118Y1613601D01*
X2325301Y1616518D01*
G01X2337343Y1599018D02*
Y1610684D01*
G01Y1607476D02*
X2337998Y1608935D01*
X2339090Y1610101D01*
X2340618Y1610684D01*
X2342146Y1610101D01*
X2343238Y1608935D01*
X2343893Y1607476D01*
Y1599018D01*
G01Y1607476D02*
X2344548Y1608935D01*
X2345639Y1610101D01*
X2347168Y1610684D01*
X2348696Y1610101D01*
X2349788Y1608935D01*
X2350443Y1607185D01*
Y1599018D01*
G01X2361393Y1610684D02*
Y1599018D01*
G01Y1615351D02*
X2360956Y1615643D01*
Y1616226D01*
X2361393Y1616518D01*
X2361830Y1616226D01*
Y1615643D01*
X2361393Y1615351D01*
G01X2378893Y1599018D02*
Y1616518D01*
G01X2393118Y1601059D02*
X2394210Y1599893D01*
X2395738Y1599018D01*
X2397048D01*
X2398358Y1599601D01*
X2399231Y1600476D01*
X2399668Y1601642D01*
X2399450Y1603393D01*
X2398576Y1604268D01*
X2394646Y1606018D01*
X2393773Y1608060D01*
X2394210Y1609518D01*
X2395083Y1610393D01*
X2396393Y1610684D01*
X2397703Y1610393D01*
X2399013Y1609518D01*
G01X2414985Y1593185D02*
X2417168Y1596101D01*
X2418260Y1599018D01*
Y1610684D01*
X2417168Y1613601D01*
X2414985Y1616518D01*
G01X2269090Y1566992D02*
X2270399Y1565534D01*
X2271928Y1564660D01*
X2273893Y1564368D01*
X2275858Y1564951D01*
X2277386Y1566118D01*
X2278478Y1568159D01*
X2278696Y1570493D01*
X2278260Y1572826D01*
X2277168Y1574285D01*
X2275639Y1575451D01*
X2274111Y1575743D01*
X2272583Y1575451D01*
X2270618Y1574285D01*
X2271273Y1581868D01*
X2277168D01*
G01X2291393Y1563785D02*
X2290956Y1564076D01*
Y1564660D01*
X2291393Y1564951D01*
X2291830Y1564660D01*
Y1564076D01*
X2291393Y1563785D01*
G01X2304090Y1566992D02*
X2305399Y1565534D01*
X2306928Y1564660D01*
X2308893Y1564368D01*
X2310858Y1564951D01*
X2312386Y1566118D01*
X2313478Y1568159D01*
X2313696Y1570493D01*
X2313260Y1572826D01*
X2312168Y1574285D01*
X2310639Y1575451D01*
X2309111Y1575743D01*
X2307583Y1575451D01*
X2305618Y1574285D01*
X2306273Y1581868D01*
X2312168D01*
G01X2322463Y1563785D02*
X2330323Y1581868D01*
G01X2339745Y1571659D02*
X2341273Y1573701D01*
X2342583Y1574868D01*
X2344330Y1575451D01*
X2345858Y1574868D01*
X2346950Y1573701D01*
X2347823Y1571951D01*
X2348041Y1569910D01*
X2347823Y1568159D01*
X2346950Y1566409D01*
X2345639Y1564951D01*
X2344111Y1564368D01*
X2342365Y1564951D01*
X2340836Y1566701D01*
X2339963Y1569326D01*
X2339745Y1572243D01*
X2340181Y1576034D01*
X2340836Y1578077D01*
X2341928Y1580118D01*
X2343456Y1581576D01*
X2344985Y1581868D01*
X2346513Y1581285D01*
X2347605Y1579826D01*
G01X2361393Y1563785D02*
X2360956Y1564076D01*
Y1564660D01*
X2361393Y1564951D01*
X2361830Y1564660D01*
Y1564076D01*
X2361393Y1563785D01*
G01X2378893Y1581868D02*
X2377146Y1581285D01*
X2375836Y1579826D01*
X2374963Y1578077D01*
X2374308Y1575743D01*
X2374090Y1573118D01*
X2374308Y1570493D01*
X2374963Y1568159D01*
X2375836Y1566409D01*
X2377146Y1564951D01*
X2378893Y1564368D01*
X2380639Y1564951D01*
X2381950Y1566409D01*
X2382823Y1568159D01*
X2383478Y1570493D01*
X2383696Y1573118D01*
X2383478Y1575743D01*
X2382823Y1578077D01*
X2381950Y1579826D01*
X2380639Y1581285D01*
X2378893Y1581868D01*
G01X2259013Y1529718D02*
Y1547218D01*
X2250934Y1534676D01*
X2261852D01*
G01X2273893Y1529135D02*
X2273456Y1529426D01*
Y1530010D01*
X2273893Y1530301D01*
X2274330Y1530010D01*
Y1529426D01*
X2273893Y1529135D01*
G01X2287245Y1544301D02*
X2288555Y1546051D01*
X2290083Y1546926D01*
X2291830Y1547218D01*
X2294013Y1546635D01*
X2295541Y1545176D01*
X2295978Y1543427D01*
X2295760Y1541676D01*
X2294886Y1540218D01*
X2290520Y1537301D01*
X2288555Y1535260D01*
X2287245Y1532342D01*
X2286808Y1529718D01*
X2295978D01*
G01X2304090Y1532342D02*
X2305399Y1530884D01*
X2306928Y1530010D01*
X2308893Y1529718D01*
X2310858Y1530301D01*
X2312386Y1531468D01*
X2313478Y1533509D01*
X2313696Y1535843D01*
X2313260Y1538176D01*
X2312168Y1539635D01*
X2310639Y1540801D01*
X2309111Y1541093D01*
X2307583Y1540801D01*
X2305618Y1539635D01*
X2306273Y1547218D01*
X2312168D01*
G01X2322463Y1529135D02*
X2330323Y1547218D01*
G01X2343893Y1529718D02*
X2345421Y1530010D01*
X2347168Y1530884D01*
X2348260Y1532342D01*
X2348696Y1534385D01*
X2348260Y1536426D01*
X2346950Y1538176D01*
X2344985Y1539051D01*
X2342801D01*
X2341491Y1539635D01*
X2340399Y1541093D01*
X2339963Y1543134D01*
X2340618Y1545176D01*
X2342146Y1546635D01*
X2343893Y1547218D01*
X2345639Y1546635D01*
X2347168Y1545176D01*
X2347823Y1543134D01*
X2347386Y1541093D01*
X2346295Y1539635D01*
X2344985Y1539051D01*
X2342801D01*
X2340836Y1538176D01*
X2339526Y1536426D01*
X2339090Y1534385D01*
X2339526Y1532342D01*
X2340618Y1530884D01*
X2342365Y1530010D01*
X2343893Y1529718D01*
G01X2361393Y1529135D02*
X2360956Y1529426D01*
Y1530010D01*
X2361393Y1530301D01*
X2361830Y1530010D01*
Y1529426D01*
X2361393Y1529135D01*
G01X2378456Y1529718D02*
X2378893Y1533509D01*
X2379548Y1536718D01*
X2380421Y1539635D01*
X2381513Y1542843D01*
X2383260Y1547218D01*
X2374526D01*
G01X2391590Y1532342D02*
X2392899Y1530884D01*
X2394428Y1530010D01*
X2396393Y1529718D01*
X2398358Y1530301D01*
X2399886Y1531468D01*
X2400978Y1533509D01*
X2401196Y1535843D01*
X2400760Y1538176D01*
X2399668Y1539635D01*
X2398139Y1540801D01*
X2396611Y1541093D01*
X2395083Y1540801D01*
X2393118Y1539635D01*
X2393773Y1547218D01*
X2399668D01*
G01X2531590Y1564368D02*
Y1581868D01*
X2535956D01*
X2537703Y1580993D01*
X2539013Y1579826D01*
X2540105Y1578077D01*
X2540978Y1576034D01*
X2541196Y1573118D01*
X2540978Y1570201D01*
X2540105Y1568159D01*
X2539013Y1566409D01*
X2537703Y1565243D01*
X2535956Y1564368D01*
X2531590D01*
G01X2549526D02*
Y1581868D01*
X2554766D01*
X2556513Y1580993D01*
X2557823Y1578951D01*
X2558260Y1576618D01*
X2557823Y1574285D01*
X2556731Y1572535D01*
X2554766Y1571659D01*
X2549526D01*
G01X2531590Y1529718D02*
Y1547218D01*
X2535956D01*
X2537703Y1546343D01*
X2539013Y1545176D01*
X2540105Y1543427D01*
X2540978Y1541384D01*
X2541196Y1538468D01*
X2540978Y1535551D01*
X2540105Y1533509D01*
X2539013Y1531759D01*
X2537703Y1530593D01*
X2535956Y1529718D01*
X2531590D01*
G01X2549526D02*
Y1547218D01*
X2554766D01*
X2556513Y1546343D01*
X2557823Y1544301D01*
X2558260Y1541968D01*
X2557823Y1539635D01*
X2556731Y1537885D01*
X2554766Y1537009D01*
X2549526D01*
G01X2518893Y1616518D02*
Y1599018D01*
G01X2513871Y1616518D02*
X2523915D01*
G01X2536393Y1599018D02*
Y1606893D01*
X2532026Y1616518D01*
G01X2540760D02*
X2536393Y1606893D01*
G01X2549526Y1599018D02*
Y1616518D01*
X2554766D01*
X2556513Y1615643D01*
X2557823Y1613601D01*
X2558260Y1611268D01*
X2557823Y1608935D01*
X2556731Y1607185D01*
X2554766Y1606309D01*
X2549526D01*
G01X2575760Y1599018D02*
X2567026D01*
Y1616518D01*
X2575760D01*
G01X2572266Y1608060D02*
X2567026D01*
G01X2619526Y1599018D02*
Y1616518D01*
X2624985D01*
X2626731Y1615643D01*
X2627823Y1614476D01*
X2628260Y1612143D01*
X2627823Y1609809D01*
X2626513Y1608351D01*
X2624985Y1607476D01*
X2619526D01*
G01X2624985D02*
X2628260Y1599018D01*
G01X2638118Y1606893D02*
X2645105D01*
X2644450Y1608935D01*
X2643358Y1610101D01*
X2641830Y1610684D01*
X2640301Y1610393D01*
X2638991Y1609518D01*
X2638118Y1607476D01*
X2637681Y1605726D01*
Y1603976D01*
X2638118Y1602226D01*
X2639210Y1600476D01*
X2640520Y1599310D01*
X2642048Y1599018D01*
X2643576Y1599601D01*
X2645105Y1601351D01*
G01X2657583Y1599018D02*
Y1613893D01*
X2658020Y1615351D01*
X2658893Y1616226D01*
X2660203Y1616518D01*
X2661513Y1615935D01*
X2662168Y1614476D01*
G01X2659548Y1609518D02*
X2655181D01*
G01X2676393Y1598435D02*
X2675956Y1598726D01*
Y1599310D01*
X2676393Y1599601D01*
X2676830Y1599310D01*
Y1598726D01*
X2676393Y1598435D01*
G01X2707026Y1599018D02*
Y1616518D01*
X2712266D01*
X2714013Y1615643D01*
X2715323Y1613601D01*
X2715760Y1611268D01*
X2715323Y1608935D01*
X2714231Y1607185D01*
X2712266Y1606309D01*
X2707026D01*
G01X2728893Y1599018D02*
Y1616518D01*
G01X2750323Y1599018D02*
Y1610684D01*
G01Y1608643D02*
X2749450Y1609809D01*
X2748139Y1610393D01*
X2746611Y1610684D01*
X2745083Y1610101D01*
X2743773Y1608935D01*
X2742899Y1607185D01*
X2742463Y1604851D01*
X2742899Y1602518D01*
X2743773Y1600768D01*
X2745083Y1599601D01*
X2746611Y1599018D01*
X2748139Y1599310D01*
X2749450Y1600184D01*
X2750323Y1601351D01*
G01X2760181Y1599018D02*
Y1610684D01*
G01Y1607768D02*
X2761055Y1609226D01*
X2762365Y1610393D01*
X2764111Y1610684D01*
X2765639Y1610393D01*
X2766950Y1609226D01*
X2767605Y1607185D01*
Y1599018D01*
G01X2778118Y1606893D02*
X2785105D01*
X2784450Y1608935D01*
X2783358Y1610101D01*
X2781830Y1610684D01*
X2780301Y1610393D01*
X2778991Y1609518D01*
X2778118Y1607476D01*
X2777681Y1605726D01*
Y1603976D01*
X2778118Y1602226D01*
X2779210Y1600476D01*
X2780520Y1599310D01*
X2782048Y1599018D01*
X2783576Y1599601D01*
X2785105Y1601351D01*
G01X2663276Y1581868D02*
Y1564368D01*
X2672010D01*
G01X2680995Y1578951D02*
X2682305Y1580701D01*
X2683833Y1581576D01*
X2685580Y1581868D01*
X2687763Y1581285D01*
X2689291Y1579826D01*
X2689728Y1578077D01*
X2689510Y1576326D01*
X2688636Y1574868D01*
X2684270Y1571951D01*
X2682305Y1569910D01*
X2680995Y1566992D01*
X2680558Y1564368D01*
X2689728D01*
G01X2698713Y1563785D02*
X2706573Y1581868D01*
G01X2715776D02*
Y1564368D01*
X2724510D01*
G01X2740263D02*
Y1581868D01*
X2732184Y1569326D01*
X2743102D01*
G01X2663276Y1547218D02*
Y1529718D01*
X2672010D01*
G01X2680995Y1544301D02*
X2682305Y1546051D01*
X2683833Y1546926D01*
X2685580Y1547218D01*
X2687763Y1546635D01*
X2689291Y1545176D01*
X2689728Y1543427D01*
X2689510Y1541676D01*
X2688636Y1540218D01*
X2684270Y1537301D01*
X2682305Y1535260D01*
X2680995Y1532342D01*
X2680558Y1529718D01*
X2689728D01*
G01X2698713Y1529135D02*
X2706573Y1547218D01*
G01X2715776D02*
Y1529718D01*
X2724510D01*
G01X2740263D02*
Y1547218D01*
X2732184Y1534676D01*
X2743102D01*
G01X2899193Y1576034D02*
Y1564368D01*
G01Y1580701D02*
X2898756Y1580993D01*
Y1581576D01*
X2899193Y1581868D01*
X2899630Y1581576D01*
Y1580993D01*
X2899193Y1580701D01*
G01X2913418Y1566409D02*
X2914510Y1565243D01*
X2916038Y1564368D01*
X2917348D01*
X2918658Y1564951D01*
X2919531Y1565826D01*
X2919968Y1566992D01*
X2919750Y1568743D01*
X2918876Y1569618D01*
X2914946Y1571368D01*
X2914073Y1573410D01*
X2914510Y1574868D01*
X2915383Y1575743D01*
X2916693Y1576034D01*
X2918003Y1575743D01*
X2919313Y1574868D01*
G01X2946671Y1564368D02*
Y1581868D01*
X2956715Y1564368D01*
Y1581868D01*
G01X2969193Y1564368D02*
X2967446Y1564660D01*
X2965918Y1565826D01*
X2964608Y1567576D01*
X2963734Y1569618D01*
X2963298Y1571951D01*
Y1574285D01*
X2963734Y1576618D01*
X2964608Y1578660D01*
X2965918Y1580409D01*
X2967446Y1581576D01*
X2969193Y1581868D01*
X2970939Y1581576D01*
X2972468Y1580409D01*
X2973778Y1578660D01*
X2974652Y1576618D01*
X2975088Y1574285D01*
Y1571951D01*
X2974652Y1569618D01*
X2973778Y1567576D01*
X2972468Y1565826D01*
X2970939Y1564660D01*
X2969193Y1564368D01*
G01X2986693Y1581868D02*
Y1564368D01*
G01X2981671Y1581868D02*
X2991715D01*
G01X3017981Y1576034D02*
Y1567868D01*
X3018855Y1565826D01*
X3020165Y1564660D01*
X3021693Y1564368D01*
X3023221Y1564660D01*
X3024531Y1565826D01*
X3025405Y1567868D01*
G01Y1564368D02*
Y1576034D01*
G01X3035918Y1566409D02*
X3037010Y1565243D01*
X3038538Y1564368D01*
X3039848D01*
X3041158Y1564951D01*
X3042031Y1565826D01*
X3042468Y1566992D01*
X3042250Y1568743D01*
X3041376Y1569618D01*
X3037446Y1571368D01*
X3036573Y1573410D01*
X3037010Y1574868D01*
X3037883Y1575743D01*
X3039193Y1576034D01*
X3040503Y1575743D01*
X3041813Y1574868D01*
G01X3053418Y1572243D02*
X3060405D01*
X3059750Y1574285D01*
X3058658Y1575451D01*
X3057130Y1576034D01*
X3055601Y1575743D01*
X3054291Y1574868D01*
X3053418Y1572826D01*
X3052981Y1571076D01*
Y1569326D01*
X3053418Y1567576D01*
X3054510Y1565826D01*
X3055820Y1564660D01*
X3057348Y1564368D01*
X3058876Y1564951D01*
X3060405Y1566701D01*
G01X3078123Y1581868D02*
Y1564368D01*
G01Y1566992D02*
X3077250Y1565534D01*
X3075939Y1564660D01*
X3074411Y1564368D01*
X3072665Y1564951D01*
X3071355Y1566409D01*
X3070481Y1568159D01*
X3070263Y1570201D01*
X3070481Y1572243D01*
X3071355Y1573993D01*
X3072665Y1575451D01*
X3074411Y1576034D01*
X3075939Y1575743D01*
X3077031Y1575159D01*
X3078123Y1573993D01*
G01X2824390Y1598435D02*
X2833996Y1611268D01*
G01X2829193Y1613601D02*
Y1596101D01*
G01X2833996Y1598435D02*
X2824390Y1611268D01*
G01X2822643Y1604851D02*
X2835743D01*
G01X2861355D02*
X2867031D01*
G01X2894390Y1599018D02*
Y1616518D01*
X2898756D01*
X2900503Y1615643D01*
X2901813Y1614476D01*
X2902905Y1612727D01*
X2903778Y1610684D01*
X2903996Y1607768D01*
X2903778Y1604851D01*
X2902905Y1602809D01*
X2901813Y1601059D01*
X2900503Y1599893D01*
X2898756Y1599018D01*
X2894390D01*
G01X2913418Y1606893D02*
X2920405D01*
X2919750Y1608935D01*
X2918658Y1610101D01*
X2917130Y1610684D01*
X2915601Y1610393D01*
X2914291Y1609518D01*
X2913418Y1607476D01*
X2912981Y1605726D01*
Y1603976D01*
X2913418Y1602226D01*
X2914510Y1600476D01*
X2915820Y1599310D01*
X2917348Y1599018D01*
X2918876Y1599601D01*
X2920405Y1601351D01*
G01X2930481Y1599018D02*
Y1610684D01*
G01Y1607768D02*
X2931355Y1609226D01*
X2932665Y1610393D01*
X2934411Y1610684D01*
X2935939Y1610393D01*
X2937250Y1609226D01*
X2937905Y1607185D01*
Y1599018D01*
G01X2951693D02*
X2950383Y1599310D01*
X2949073Y1600476D01*
X2948199Y1602518D01*
X2947763Y1604851D01*
X2948199Y1607185D01*
X2949073Y1609226D01*
X2950383Y1610393D01*
X2951693Y1610684D01*
X2953003Y1610393D01*
X2954313Y1609226D01*
X2955186Y1607185D01*
X2955405Y1604851D01*
X2955186Y1602518D01*
X2954313Y1600476D01*
X2953003Y1599310D01*
X2951693Y1599018D01*
G01X2969193Y1616518D02*
Y1599018D01*
G01X2966136Y1610684D02*
X2972250D01*
G01X2983418Y1606893D02*
X2990405D01*
X2989750Y1608935D01*
X2988658Y1610101D01*
X2987130Y1610684D01*
X2985601Y1610393D01*
X2984291Y1609518D01*
X2983418Y1607476D01*
X2982981Y1605726D01*
Y1603976D01*
X2983418Y1602226D01*
X2984510Y1600476D01*
X2985820Y1599310D01*
X2987348Y1599018D01*
X2988876Y1599601D01*
X2990405Y1601351D01*
G01X3000918Y1601059D02*
X3002010Y1599893D01*
X3003538Y1599018D01*
X3004848D01*
X3006158Y1599601D01*
X3007031Y1600476D01*
X3007468Y1601642D01*
X3007250Y1603393D01*
X3006376Y1604268D01*
X3002446Y1606018D01*
X3001573Y1608060D01*
X3002010Y1609518D01*
X3002883Y1610393D01*
X3004193Y1610684D01*
X3005503Y1610393D01*
X3006813Y1609518D01*
G01X3039193Y1616518D02*
Y1599018D01*
G01X3036136Y1610684D02*
X3042250D01*
G01X3052981Y1599018D02*
Y1616518D01*
G01Y1608060D02*
X3054073Y1609518D01*
X3055165Y1610393D01*
X3056911Y1610684D01*
X3058221Y1610393D01*
X3059750Y1609226D01*
X3060405Y1607476D01*
Y1599018D01*
G01X3078123D02*
Y1610684D01*
G01Y1608643D02*
X3077250Y1609809D01*
X3075939Y1610393D01*
X3074411Y1610684D01*
X3072883Y1610101D01*
X3071573Y1608935D01*
X3070699Y1607185D01*
X3070263Y1604851D01*
X3070699Y1602518D01*
X3071573Y1600768D01*
X3072883Y1599601D01*
X3074411Y1599018D01*
X3075939Y1599310D01*
X3077250Y1600184D01*
X3078123Y1601351D01*
G01X3091693Y1616518D02*
Y1599018D01*
G01X3088636Y1610684D02*
X3094750D01*
G01X3126693Y1616518D02*
Y1599018D01*
G01X3123636Y1610684D02*
X3129750D01*
G01X3140481Y1599018D02*
Y1616518D01*
G01Y1608060D02*
X3141573Y1609518D01*
X3142665Y1610393D01*
X3144411Y1610684D01*
X3145721Y1610393D01*
X3147250Y1609226D01*
X3147905Y1607476D01*
Y1599018D01*
G01X3161693Y1610684D02*
Y1599018D01*
G01Y1615351D02*
X3161256Y1615643D01*
Y1616226D01*
X3161693Y1616518D01*
X3162130Y1616226D01*
Y1615643D01*
X3161693Y1615351D01*
G01X3175918Y1601059D02*
X3177010Y1599893D01*
X3178538Y1599018D01*
X3179848D01*
X3181158Y1599601D01*
X3182031Y1600476D01*
X3182468Y1601642D01*
X3182250Y1603393D01*
X3181376Y1604268D01*
X3177446Y1606018D01*
X3176573Y1608060D01*
X3177010Y1609518D01*
X3177883Y1610393D01*
X3179193Y1610684D01*
X3180503Y1610393D01*
X3181813Y1609518D01*
G01X3211573Y1616518D02*
X3216813D01*
G01X3214193D02*
Y1599018D01*
G01X3211573D02*
X3216813D01*
G01X3225143D02*
Y1610684D01*
G01Y1607476D02*
X3225798Y1608935D01*
X3226890Y1610101D01*
X3228418Y1610684D01*
X3229946Y1610101D01*
X3231038Y1608935D01*
X3231693Y1607476D01*
Y1599018D01*
G01Y1607476D02*
X3232348Y1608935D01*
X3233439Y1610101D01*
X3234968Y1610684D01*
X3236496Y1610101D01*
X3237588Y1608935D01*
X3238243Y1607185D01*
Y1599018D01*
G01X3245263Y1593185D02*
Y1610684D01*
G01Y1608060D02*
X3246355Y1609518D01*
X3247446Y1610393D01*
X3249193Y1610684D01*
X3250721Y1610393D01*
X3252250Y1608935D01*
X3252905Y1606893D01*
X3253123Y1604851D01*
X3252905Y1602809D01*
X3252250Y1600768D01*
X3250939Y1599601D01*
X3249193Y1599018D01*
X3247665Y1599310D01*
X3246136Y1600184D01*
X3245263Y1601351D01*
G01X3263418Y1606893D02*
X3270405D01*
X3269750Y1608935D01*
X3268658Y1610101D01*
X3267130Y1610684D01*
X3265601Y1610393D01*
X3264291Y1609518D01*
X3263418Y1607476D01*
X3262981Y1605726D01*
Y1603976D01*
X3263418Y1602226D01*
X3264510Y1600476D01*
X3265820Y1599310D01*
X3267348Y1599018D01*
X3268876Y1599601D01*
X3270405Y1601351D01*
G01X3288123Y1616518D02*
Y1599018D01*
G01Y1601642D02*
X3287250Y1600184D01*
X3285939Y1599310D01*
X3284411Y1599018D01*
X3282665Y1599601D01*
X3281355Y1601059D01*
X3280481Y1602809D01*
X3280263Y1604851D01*
X3280481Y1606893D01*
X3281355Y1608643D01*
X3282665Y1610101D01*
X3284411Y1610684D01*
X3285939Y1610393D01*
X3287031Y1609809D01*
X3288123Y1608643D01*
G01X3305623Y1599018D02*
Y1610684D01*
G01Y1608643D02*
X3304750Y1609809D01*
X3303439Y1610393D01*
X3301911Y1610684D01*
X3300383Y1610101D01*
X3299073Y1608935D01*
X3298199Y1607185D01*
X3297763Y1604851D01*
X3298199Y1602518D01*
X3299073Y1600768D01*
X3300383Y1599601D01*
X3301911Y1599018D01*
X3303439Y1599310D01*
X3304750Y1600184D01*
X3305623Y1601351D01*
G01X3315481Y1599018D02*
Y1610684D01*
G01Y1607768D02*
X3316355Y1609226D01*
X3317665Y1610393D01*
X3319411Y1610684D01*
X3320939Y1610393D01*
X3322250Y1609226D01*
X3322905Y1607185D01*
Y1599018D01*
G01X3340186Y1609226D02*
X3338658Y1610393D01*
X3337348Y1610684D01*
X3335601Y1610101D01*
X3334291Y1608935D01*
X3333418Y1606893D01*
X3333199Y1604851D01*
X3333418Y1602809D01*
X3334291Y1601059D01*
X3335601Y1599601D01*
X3337348Y1599018D01*
X3338876Y1599601D01*
X3340186Y1600768D01*
G01X3350918Y1606893D02*
X3357905D01*
X3357250Y1608935D01*
X3356158Y1610101D01*
X3354630Y1610684D01*
X3353101Y1610393D01*
X3351791Y1609518D01*
X3350918Y1607476D01*
X3350481Y1605726D01*
Y1603976D01*
X3350918Y1602226D01*
X3352010Y1600476D01*
X3353320Y1599310D01*
X3354848Y1599018D01*
X3356376Y1599601D01*
X3357905Y1601351D01*
G01X0Y-137756D02*
G03X15000Y-152756I15000J0D01*
G01X0Y-137756D02*
G03X15000Y-152756I15000J0D01*
G01X0Y-11811D02*
Y-137756D01*
G01Y-11811D02*
Y-137756D01*
G01X854331Y-152756D02*
X15000D01*
G01X854331D02*
X15000D01*
G01X23622Y-7874D02*
G03Y0I0J3937D01*
G01Y-7874D02*
G03Y0I0J3937D01*
G01X0Y3937D02*
G03X3937Y0I3937J0D01*
G01Y-7874D02*
X23622D01*
G01X0Y3937D02*
G03X3937Y0I3937J0D01*
G01Y-7874D02*
X23622D01*
G01X3937D02*
G03X0Y-11811I0J-3937D01*
G01X3937Y-7874D02*
G03X0Y-11811I0J-3937D01*
G01X3937Y0D02*
X397638D01*
G01X3937D02*
X397638D01*
G01X0Y1370866D02*
Y3937D01*
G01Y1370866D02*
Y3937D01*
G01X3937Y1374803D02*
G03X0Y1370866I0J-3937D01*
G01X3937Y1374803D02*
G03X0Y1370866I0J-3937D01*
G01X23622Y1374803D02*
G03Y1382677I0J3937D01*
G01Y1374803D02*
G03Y1382677I0J3937D01*
G01X3937D02*
X23622D01*
G01X0Y1386614D02*
G03X3937Y1382677I3937J0D01*
G01D02*
X23622D01*
G01X0Y1386614D02*
G03X3937Y1382677I3937J0D01*
G01Y1374803D02*
X746850D01*
G01D02*
X3937D01*
G01X0Y1386614D02*
Y1643268D01*
G01Y1386614D02*
Y1643268D01*
G01X15000Y1658268D02*
G03X0Y1643268I0J-15000D01*
G01X15000Y1658268D02*
G03X0Y1643268I0J-15000D01*
G01X775591Y1658268D02*
X15000D01*
G01X775591D02*
X15000D01*
G01X54331Y-7874D02*
X323228D01*
G01X54331D02*
X323228D01*
G01X54331Y0D02*
G03Y-7874I0J-3937D01*
G01Y0D02*
G03Y-7874I0J-3937D01*
G01Y1382677D02*
G03Y1374803I0J-3937D01*
G01Y1382677D02*
G03Y1374803I0J-3937D01*
G01Y1382677D02*
X353740D01*
G01X54331D02*
X353740D01*
G01X114295Y378885D02*
G03X148106I16905J-13531D01*
G01X114295D02*
G03X148106I16905J-13531D01*
G01X114295D02*
G03X121220Y392016I-30737J24602D01*
G01X114295Y378885D02*
G03X121220Y392016I-30737J24602D01*
G01X114295Y831641D02*
G03X121220Y844772I-30737J24601D01*
G01X114295Y831641D02*
G03X121220Y844772I-30737J24602D01*
G01X114295Y831641D02*
G03X148106I16905J-13531D01*
G01X114295D02*
G03X148106I16905J-13531D01*
G01X114295Y1284397D02*
G03X148106I16905J-13531D01*
G01X114295D02*
G03X148106I16905J-13531D01*
G01X114295D02*
G03X121220Y1297528I-30737J24601D01*
G01X114295Y1284397D02*
G03X121220Y1297528I-30737J24602D01*
G01X141181Y392016D02*
G03X121220I-9980J-3039D01*
G01X141181D02*
G03X148106Y378885I37662J11471D01*
G01X141181Y392016D02*
G03X121220I-9980J-3039D01*
G01X141181D02*
G03X148106Y378885I37662J11471D01*
G01X141181Y844772D02*
G03X148106Y831641I37662J11471D01*
G01X141181Y844772D02*
G03X148106Y831641I37662J11471D01*
G01X141181Y844772D02*
G03X121220I-9980J-3040D01*
G01X141181D02*
G03X121220I-9980J-3039D01*
G01X141181Y1297528D02*
G03X121220I-9980J-3040D01*
G01X141181D02*
G03X148106Y1284397I37662J11471D01*
G01X141181Y1297528D02*
G03X121220I-9980J-3040D01*
G01X141181D02*
G03X148106Y1284397I37662J11471D01*
G01X323228Y-7874D02*
G03Y0I0J3937D01*
G01Y-7874D02*
G03Y0I0J3937D01*
G01X362598D02*
G03Y-7874I0J-3937D01*
G01Y0D02*
G03Y-7874I0J-3937D01*
G01X362327Y378885D02*
G03X396138I16905J-13531D01*
G01X362327D02*
G03X396138I16905J-13531D01*
G01X362327D02*
G03X369252Y392016I-30737J24602D01*
G01X362327Y378885D02*
G03X369252Y392016I-30737J24602D01*
G01X362327Y831641D02*
G03X369252Y844772I-30737J24602D01*
G01X362327Y831641D02*
G03X369252Y844772I-30737J24602D01*
G01X362327Y831641D02*
G03X396138I16905J-13531D01*
G01X362327D02*
G03X396138I16905J-13531D01*
G01X362327Y1284397D02*
G03X396138I16905J-13531D01*
G01X362327D02*
G03X396138I16905J-13531D01*
G01X362327D02*
G03X369252Y1297528I-30737J24602D01*
G01X362327Y1284397D02*
G03X369252Y1297528I-30737J24602D01*
G01X353740Y1374803D02*
G03Y1382677I0J3937D01*
G01Y1374803D02*
G03Y1382677I0J3937D01*
G01X401575Y3937D02*
Y55118D01*
G01X397638Y0D02*
G03X401575Y3937I0J3937D01*
G01X409449D02*
Y51181D01*
G01X397638Y-7874D02*
G03X409449Y3937I0J11811D01*
G01X397638Y0D02*
G03X401575Y3937I0J3937D01*
G01D02*
Y55118D01*
G01X409449Y3937D02*
Y51181D01*
G01X397638Y-7874D02*
G03X409449Y3937I0J11811D01*
G01X362598Y-7874D02*
X397638D01*
G01X362598D02*
X397638D01*
G01X405512Y59055D02*
G03X401575Y55118I0J-3937D01*
G01X405512Y59055D02*
G03X401575Y55118I0J-3937D01*
G01X405512Y59055D02*
X586614D01*
G01X409449Y51181D02*
X582677D01*
G01X405512Y59055D02*
X586614D01*
G01X409449Y51181D02*
X582677D01*
G01X389213Y392016D02*
G03X396138Y378885I37662J11471D01*
G01X389213Y392016D02*
G03X396138Y378885I37662J11471D01*
G01X389213Y392016D02*
G03X369252I-9981J-3039D01*
G01X389213D02*
G03X369252I-9981J-3039D01*
G01X389213Y844772D02*
G03X396138Y831641I37662J11471D01*
G01X389213Y844772D02*
G03X396138Y831641I37662J11471D01*
G01X389213Y844772D02*
G03X369252I-9981J-3040D01*
G01X389213D02*
G03X369252I-9981J-3039D01*
G01X389213Y1297528D02*
G03X396138Y1284397I37662J11471D01*
G01X389213Y1297528D02*
G03X396138Y1284397I37662J11471D01*
G01X389213Y1297528D02*
G03X369252I-9981J-3040D01*
G01X389213D02*
G03X369252I-9981J-3040D01*
G01X393110Y1382677D02*
G03Y1374803I0J-3937D01*
G01Y1382677D02*
X692520D01*
G01X393110D02*
X692520D01*
G01X393110D02*
G03Y1374803I0J-3937D01*
G01X523327Y829921D02*
G03X483169I-20079J0D01*
G01X523327D02*
G03I-20079J0D01*
G01X483169D02*
G03X523327I20079J0D01*
G01X594488Y-7874D02*
X628765D01*
G01X594488D02*
X628765D01*
G01X590551Y55118D02*
Y3937D01*
G01D02*
G03X594488Y0I3937J0D01*
G01X582677Y51181D02*
Y3937D01*
G01D02*
G03X594488Y-7874I11811J0D01*
G01X590551Y55118D02*
Y3937D01*
G01D02*
G03X594488Y0I3937J0D01*
G01X582677Y51181D02*
Y3937D01*
G01D02*
G03X594488Y-7874I11811J0D01*
G01Y0D02*
X783465D01*
G01X594488D02*
X783465D01*
G01X590551Y55118D02*
G03X586614Y59055I-3937J0D01*
G01X590551Y55118D02*
G03X586614Y59055I-3937J0D01*
G01X628765Y-7874D02*
G03Y0I0J3937D01*
G01Y-7874D02*
G03Y0I0J3937D01*
G01X610358Y378885D02*
G03X644169I16906J-13531D01*
G01X610358D02*
G03X644169I16906J-13531D01*
G01X637244Y392016D02*
G03X644169Y378885I37662J11471D01*
G01X637244Y392016D02*
G03X644169Y378885I37662J11471D01*
G01X637244Y392016D02*
G03X617283I-9980J-3039D01*
G01X637244D02*
G03X617283I-9980J-3039D01*
G01X610358Y378885D02*
G03X617283Y392016I-30737J24602D01*
G01X610358Y378885D02*
G03X617283Y392016I-30737J24602D01*
G01X637244Y844772D02*
G03X644169Y831641I37662J11471D01*
G01X637244Y844772D02*
G03X644169Y831641I37662J11471D01*
G01X610358D02*
G03X617283Y844772I-30737J24601D01*
G01X610358Y831641D02*
G03X617283Y844772I-30737J24602D01*
G01X610358Y831641D02*
G03X644169I16906J-13531D01*
G01X610358D02*
G03X644169I16906J-13531D01*
G01X637244Y844772D02*
G03X617283I-9980J-3040D01*
G01X637244D02*
G03X617283I-9980J-3039D01*
G01X610358Y1284397D02*
G03X644169I16906J-13531D01*
G01X610358D02*
G03X644169I16906J-13531D01*
G01X637244Y1297528D02*
G03X644169Y1284397I37662J11471D01*
G01X637244Y1297528D02*
G03X644169Y1284397I37662J11471D01*
G01X610358D02*
G03X617283Y1297528I-30737J24601D01*
G01X637244D02*
G03X617283I-9980J-3040D01*
G01X610358Y1284397D02*
G03X617283Y1297528I-30737J24602D01*
G01X637244D02*
G03X617283I-9980J-3040D01*
G01X659474Y0D02*
G03Y-7874I0J-3937D01*
G01Y0D02*
G03Y-7874I0J-3937D01*
G01D02*
X780203D01*
G01X659474D02*
X780203D01*
G01X692520Y1374803D02*
G03Y1382677I0J3937D01*
G01Y1374803D02*
G03Y1382677I0J3937D01*
G01X746850Y1374803D02*
G03X750787Y1378740I0J3937D01*
G01X746850Y1374803D02*
G03X750787Y1378740I0J3937D01*
G01X723228Y1382677D02*
G03Y1374803I0J-3937D01*
G01Y1382677D02*
X742913D01*
G01X723228D02*
X742913D01*
G01X723228D02*
G03Y1374803I0J-3937D01*
G01X742913Y1464567D02*
Y1382677D01*
G01Y1464567D02*
Y1382677D01*
G01X754724Y1476378D02*
G03X742913Y1464567I0J-11811D01*
G01X754724Y1476378D02*
G03X742913Y1464567I0J-11811D01*
G01X862205Y-7874D02*
X791339D01*
G01X787402Y-3937D02*
G03X791339Y-7874I3937J0D01*
G01X787402Y-3937D02*
G03X791339Y-7874I3937J0D01*
G01D02*
X862205D01*
G01X858268Y-15748D02*
X791339D01*
G01X858268D02*
X791339D01*
G01X787402Y-3937D02*
G03X783465Y0I-3937J0D01*
G01X787402Y-3937D02*
G03X783465Y0I-3937J0D01*
G01X780203Y-7874D02*
G03X791339Y-15748I11136J3937D01*
G01X780203Y-7874D02*
G03X791339Y-15748I11136J3937D01*
G01X779551Y264712D02*
G03X813362I16905J-13531D01*
G01X779551D02*
G03X813362I16905J-13531D01*
G01X779551D02*
G03X786476Y277843I-30737J24601D01*
G01X806437D02*
G03X786476I-9981J-3040D01*
G01X779551Y264712D02*
G03X786476Y277843I-30737J24602D01*
G01X806437D02*
G03X786476I-9981J-3040D01*
G01X779551Y737153D02*
G03X786476Y750284I-30737J24601D01*
G01X779551Y737154D02*
G03X786476Y750284I-30736J24602D01*
G01X779551Y737153D02*
G03X813362I16905J-13531D01*
G01X779551D02*
G03X813362I16905J-13531D01*
G01X806437Y750284D02*
G03X786476I-9981J-3040D01*
G01X806437D02*
G03X786476I-9981J-3040D01*
G01X750787Y1464567D02*
Y1378740D01*
G01Y1464567D02*
Y1378740D01*
G01X783465Y1468504D02*
G03X787402Y1472441I0J3937D01*
G01X783465Y1468504D02*
G03X787402Y1472441I0J3937D01*
G01X783465Y1468504D02*
X754724D01*
G01D02*
G03X750787Y1464567I0J-3937D01*
G01X783465Y1468504D02*
X754724D01*
G01D02*
G03X750787Y1464567I0J-3937D01*
G01X779528Y1476378D02*
X754724D01*
G01X779528D02*
X754724D01*
G01X787402Y1654331D02*
Y1472441D01*
G01X779528Y1596063D02*
Y1476378D01*
G01X787402Y1654331D02*
Y1472441D01*
G01X779528Y1596063D02*
Y1476378D01*
G01X787402Y1596063D02*
G03X779528I-3937J0D01*
G01X787402D02*
G03X779528I-3937J0D01*
G01X1216535Y1658268D02*
X791339D01*
G01D02*
G03X787402Y1654331I0J-3937D01*
G01X779528D02*
G03X775591Y1658268I-3937J0D01*
G01X1216535D02*
X791339D01*
G01D02*
G03X787402Y1654331I0J-3937D01*
G01X779528D02*
G03X775591Y1658268I-3937J0D01*
G01X779528Y1654331D02*
Y1626772D01*
G01D02*
G03X787402I3937J0D01*
G01X779528Y1654331D02*
Y1626772D01*
G01D02*
G03X787402I3937J0D01*
G01X806437Y277843D02*
G03X813362Y264712I37662J11471D01*
G01X806437Y277843D02*
G03X813362Y264712I37662J11471D01*
G01X806437Y750284D02*
G03X813362Y737153I37662J11471D01*
G01X806437Y750284D02*
G03X813362Y737154I37661J11472D01*
G01X866142Y-148819D02*
Y-11811D01*
G01Y-148819D02*
G03X870079Y-152756I3937J0D01*
G01X866142Y-11811D02*
Y-148819D01*
G01D02*
G03X870079Y-152756I3937J0D01*
G01X866142Y-129134D02*
G03X858268I-3937J0D01*
G01X866142D02*
G03X858268I-3937J0D01*
G01Y-148819D02*
Y-129134D01*
G01X854331Y-152756D02*
G03X858268Y-148819I0J3937D01*
G01D02*
Y-129134D01*
G01X854331Y-152756D02*
G03X858268Y-148819I0J3937D01*
G01X1177165Y-152756D02*
X870079D01*
G01D02*
X1177165D01*
G01X858268Y-98425D02*
Y-15748D01*
G01Y-98425D02*
Y-15748D01*
G01Y-98425D02*
G03X866142I3937J0D01*
G01X858268D02*
G03X866142I3937J0D01*
G01Y-11811D02*
G03X862205Y-7874I-3937J0D01*
G01X866142Y-11811D02*
G03X862205Y-7874I-3937J0D01*
G01X927032Y-57820D02*
G03X962731I17850J-12259D01*
G01X927032Y-57821D02*
G03X962732I17850J-12258D01*
G01X927032Y-57820D02*
G03X935199Y-42571I-64908J44575D01*
G01X954565D02*
G03X935199I-9683J-3885D01*
G01X927032Y-57821D02*
G03X935199Y-42571I-64909J44573D01*
G01X954564D02*
G03X935199I-9682J-3885D01*
G01X944512Y1089122D02*
G03X978323I16905J-13531D01*
G01X944512Y1089121D02*
G03X978323I16905J-13531D01*
G01X944512Y1431641D02*
G03X978323I16905J-13531D01*
G01X944512D02*
G03X978323I16905J-13531D01*
G01X954565Y-42571D02*
G03X962731Y-57820I73077J29322D01*
G01X954564Y-42570D02*
G03X962732Y-57821I73076J29324D01*
G01X971398Y1102252D02*
G03X978323Y1089122I37661J11472D01*
G01X971398Y1102252D02*
G03X978323Y1089121I37662J11471D01*
G01X971398Y1102252D02*
G03X951437I-9980J-3039D01*
G01X971398D02*
G03X951437I-9980J-3039D01*
G01X944512Y1089122D02*
G03X951437Y1102252I-30737J24602D01*
G01X944512Y1089121D02*
G03X951437Y1102252I-30737J24602D01*
G01X971398Y1444772D02*
G03X978323Y1431641I37662J11471D01*
G01X971398Y1444772D02*
G03X978323Y1431641I37662J11471D01*
G01X971398Y1444772D02*
G03X951437I-9980J-3040D01*
G01X944512Y1431641D02*
G03X951437Y1444772I-30737J24602D01*
G01X944512Y1431641D02*
G03X951437Y1444772I-30737J24602D01*
G01X971398D02*
G03X951437I-9980J-3039D01*
G01X1181102Y-148819D02*
Y-3937D01*
G01X1177165Y-152756D02*
G03X1181102Y-148819I0J3937D01*
G01X1177165Y-152756D02*
G03X1181102Y-148819I0J3937D01*
G01D02*
Y-3937D01*
G01Y-94488D02*
G03X1188976I3937J0D01*
G01X1181102D02*
G03X1188976I3937J0D01*
G01Y-125197D02*
G03X1181102I-3937J0D01*
G01X1188976D02*
G03X1181102I-3937J0D01*
G01X1185039Y0D02*
G03X1181102Y-3937I0J-3937D01*
G01X1185039Y0D02*
G03X1181102Y-3937I0J-3937D01*
G01X1164984Y557626D02*
G03X1198795I16906J-13531D01*
G01X1164984Y557625D02*
G03X1198795I16906J-13531D01*
G01X1191870Y570756D02*
G03X1171909I-9980J-3039D01*
G01X1191870D02*
G03X1171909I-9980J-3039D01*
G01X1164984Y557626D02*
G03X1171909Y570756I-30736J24602D01*
G01X1164984Y557625D02*
G03X1171909Y570756I-30737J24602D01*
G01X1164984Y971011D02*
G03X1198795I16906J-13531D01*
G01X1164984D02*
G03X1198795I16906J-13531D01*
G01X1191870Y984142D02*
G03X1171909I-9980J-3040D01*
G01X1191870D02*
G03X1171909I-9980J-3039D01*
G01X1164984Y971011D02*
G03X1171909Y984142I-30737J24602D01*
G01X1164984Y971011D02*
G03X1171909Y984142I-30737J24602D01*
G01X1164173Y1378740D02*
Y1468504D01*
G01X1930906Y1374803D02*
X1168110D01*
G01X1164173Y1378740D02*
G03X1168110Y1374803I3937J0D01*
G01X1172047Y1382677D02*
Y1464567D01*
G01X1195669Y1382677D02*
X1172047D01*
G01X1930906Y1374803D02*
X1168110D01*
G01X1164173Y1378740D02*
G03X1168110Y1374804I3937J1D01*
G01X1164173Y1378740D02*
Y1468504D01*
G01X1172047Y1382677D02*
Y1464567D01*
G01X1195669Y1382677D02*
X1172047D01*
G01X1168110Y1472441D02*
G03X1164173Y1468504I0J-3937D01*
G01X1168110Y1472441D02*
G03X1164173Y1468504I0J-3937D01*
G01X1172047Y1464567D02*
X1216535D01*
G01X1172047D02*
X1216535D01*
G01X1168110Y1472441D02*
X1216535D01*
G01X1168110D02*
X1216535D01*
G01X1164984Y1561563D02*
G03X1171909Y1574693I-30736J24602D01*
G01X1164984Y1561562D02*
G03X1171909Y1574693I-30737J24602D01*
G01X1164984Y1561563D02*
G03X1198795I16906J-13531D01*
G01X1164984Y1561562D02*
G03X1198795I16906J-13531D01*
G01X1191870Y1574693D02*
G03X1171909I-9980J-3039D01*
G01X1191870D02*
G03X1171909I-9980J-3039D01*
G01X1188976Y-148819D02*
Y-125197D01*
G01Y-148819D02*
G03X1192913Y-152756I3937J0D01*
G01X1188976Y-148819D02*
Y-125197D01*
G01Y-148819D02*
G03X1192913Y-152756I3937J0D01*
G01D02*
X1919843D01*
G01X1192913D02*
X1919843D01*
G01X1188976Y-94488D02*
Y-7874D01*
G01Y-94488D02*
Y-7874D01*
G01X1185039Y0D02*
X1366142D01*
G01X1188976Y-7874D02*
X1315748D01*
G01X1185039Y0D02*
X1366142D01*
G01X1188976Y-7874D02*
X1315748D01*
G01X1191870Y570756D02*
G03X1198795Y557626I37662J11472D01*
G01X1191870Y570756D02*
G03X1198795Y557626I37662J11472D01*
G01X1191870Y984142D02*
G03X1198795Y971011I37662J11471D01*
G01X1191870Y984142D02*
G03X1198795Y971011I37662J11471D01*
G01X1524606Y1382677D02*
X1226378D01*
G01X1524606D02*
X1226378D01*
G01X1195669Y1374803D02*
G03Y1382677I0J3937D01*
G01X1226378D02*
G03Y1374803I0J-3937D01*
G01X1195669D02*
G03Y1382677I0J3937D01*
G01X1226378D02*
G03Y1374803I0J-3937D01*
G01X1216535Y1464567D02*
G03X1228346Y1476378I0J11811D01*
G01X1216535Y1464567D02*
G03X1228346Y1476378I0J11811D01*
G01Y1592126D02*
Y1476378D01*
G01Y1592126D02*
Y1476378D01*
G01X1220472Y1654331D02*
Y1476378D01*
G01X1216535Y1472441D02*
G03X1220472Y1476378I0J3937D01*
G01X1216535Y1472441D02*
G03X1220472Y1476378I0J3937D01*
G01D02*
Y1654331D01*
G01X1191870Y1574693D02*
G03X1198795Y1561563I37662J11472D01*
G01X1191870Y1574693D02*
G03X1198795Y1561562I37662J11471D01*
G01X1228346Y1592126D02*
G03X1220472I-3937J0D01*
G01X1228346D02*
G03X1220472I-3937J0D01*
G01X1232283Y1658268D02*
X1442382D01*
G01X1232283D02*
G03X1228346Y1654331I0J-3937D01*
G01X1232283Y1658268D02*
X1442382D01*
G01X1232283D02*
G03X1228346Y1654331I0J-3937D01*
G01D02*
Y1622835D01*
G01Y1654331D02*
Y1622835D01*
G01X1220472Y1654331D02*
G03X1216535Y1658268I-3937J0D01*
G01X1220472Y1654331D02*
G03X1216535Y1658268I-3937J0D01*
G01X1220472Y1622835D02*
G03X1228346I3937J0D01*
G01X1220472D02*
G03X1228346I3937J0D01*
G01X1284965Y378885D02*
G03X1318776I16906J-13531D01*
G01X1284965D02*
G03X1318775I16905J-13531D01*
G01X1284965Y831641D02*
G03X1318776I16906J-13531D01*
G01X1284965D02*
G03X1318775I16905J-13531D01*
G01X1284965Y1284397D02*
G03X1318776I16906J-13531D01*
G01X1284965D02*
G03X1318775I16905J-13531D01*
G01X1315748Y-7874D02*
G03Y0I0J3937D01*
G01Y-7874D02*
G03Y0I0J3937D01*
G01X1311850Y392016D02*
G03X1291890I-9980J-3040D01*
G01X1311850D02*
G03X1318776Y378885I37662J11473D01*
G01X1311851Y392016D02*
G03X1291890I-9980J-3039D01*
G01X1311851D02*
G03X1318775Y378885I37663J11469D01*
G01X1284965D02*
G03X1291890Y392016I-30737J24602D01*
G01X1284965Y378885D02*
G03X1291890Y392016I-30737J24602D01*
G01X1284965Y831641D02*
G03X1291890Y844772I-30737J24602D01*
G01X1311850D02*
G03X1318776Y831641I37662J11473D01*
G01X1284965D02*
G03X1291890Y844772I-30737J24602D01*
G01X1311851D02*
G03X1318775Y831641I37663J11469D01*
G01X1311850Y844772D02*
G03X1291890I-9980J-3040D01*
G01X1311851D02*
G03X1291890I-9980J-3039D01*
G01X1284965Y1284397D02*
G03X1291890Y1297528I-30737J24602D01*
G01X1311850D02*
G03X1291890I-9980J-3040D01*
G01X1311850D02*
G03X1318776Y1284397I37661J11473D01*
G01X1284965D02*
G03X1291890Y1297528I-30737J24602D01*
G01X1311851D02*
G03X1291890I-9980J-3040D01*
G01X1311851D02*
G03X1318775Y1284397I37663J11469D01*
G01X1377953Y3937D02*
Y51181D01*
G01Y3937D02*
Y51181D01*
G01X1370079Y3937D02*
Y55118D01*
G01X1366142Y0D02*
G03X1370079Y3937I0J3937D01*
G01X1366142Y-7874D02*
G03X1377953Y3937I0J11811D01*
G01X1346457Y-7874D02*
X1366142D01*
G01Y0D02*
G03X1370079Y3937I0J3937D01*
G01D02*
Y55118D01*
G01X1346457Y-7874D02*
X1366142D01*
G01D02*
G03X1377953Y3937I0J11811D01*
G01X1346457Y0D02*
G03Y-7874I0J-3937D01*
G01Y0D02*
G03Y-7874I0J-3937D01*
G01X1374016Y59055D02*
G03X1370079Y55118I0J-3937D01*
G01X1374016Y59056D02*
G03X1370079Y55118I0J-3937D01*
G01X1374016Y59055D02*
X1555118D01*
G01X1377953Y51181D02*
X1551181D01*
G01X1374016Y59055D02*
X1555118D01*
G01X1377953Y51181D02*
X1551181D01*
G01X1442382Y1658268D02*
G03X1450256I3937J0D01*
G01X1442382D02*
G03X1450256I3937J0D01*
G01D02*
X1919843D01*
G01X1450256D02*
X1919843D01*
G01X1562992Y0D02*
X1930906D01*
G01X1559055Y55118D02*
Y3937D01*
G01D02*
G03X1562992Y0I3937J0D01*
G01Y-7874D02*
X1593701D01*
G01X1559055Y55118D02*
Y3937D01*
G01D02*
G03X1562992Y0I3937J0D01*
G01D02*
X1930906D01*
G01X1562992Y-7874D02*
X1593701D01*
G01X1551181Y51181D02*
Y3937D01*
G01D02*
G03X1562992Y-7874I11811J0D01*
G01X1551181Y51181D02*
Y3937D01*
G01D02*
G03X1562992Y-7874I11811J0D01*
G01X1559055Y55118D02*
G03X1555118Y59055I-3937J0D01*
G01X1559055Y55118D02*
G03X1555118Y59055I-3937J0D01*
G01X1532996Y378885D02*
G03X1566807I16906J-13531D01*
G01X1532996D02*
G03X1566807I16906J-13531D01*
G01X1559882Y392016D02*
G03X1566807Y378885I37662J11471D01*
G01X1559882Y392016D02*
G03X1566807Y378885I37662J11471D01*
G01X1559882Y392016D02*
G03X1539921I-9980J-3039D01*
G01X1559882D02*
G03X1539921I-9980J-3039D01*
G01X1532996Y378885D02*
G03X1539921Y392016I-30737J24602D01*
G01X1532996Y378885D02*
G03X1539921Y392016I-30737J24602D01*
G01X1559882Y844772D02*
G03X1566807Y831641I37662J11471D01*
G01X1559882Y844772D02*
G03X1566807Y831641I37662J11471D01*
G01X1532996D02*
G03X1539921Y844772I-30737J24602D01*
G01X1532996Y831641D02*
G03X1539921Y844772I-30737J24602D01*
G01X1532996Y831641D02*
G03X1566807I16906J-13531D01*
G01X1532996D02*
G03X1566807I16906J-13531D01*
G01X1559882Y844772D02*
G03X1539921I-9980J-3040D01*
G01X1559882D02*
G03X1539921I-9980J-3039D01*
G01X1532996Y1284397D02*
G03X1566807I16906J-13531D01*
G01X1532996D02*
G03X1566807I16906J-13531D01*
G01X1559882Y1297528D02*
G03X1566807Y1284397I37662J11471D01*
G01X1559882Y1297528D02*
G03X1566807Y1284397I37662J11471D01*
G01X1559882Y1297528D02*
G03X1539921I-9980J-3040D01*
G01X1532996Y1284397D02*
G03X1539921Y1297528I-30737J24602D01*
G01X1532996Y1284397D02*
G03X1539921Y1297528I-30737J24602D01*
G01X1559882D02*
G03X1539921I-9980J-3040D01*
G01X1563976Y1382677D02*
G03Y1374803I0J-3937D01*
G01Y1382677D02*
G03Y1374803I0J-3937D01*
G01X1524606D02*
G03Y1382677I0J3937D01*
G01Y1374803D02*
G03Y1382677I0J3937D01*
G01X1864567D02*
X1563976D01*
G01X1864567D02*
X1563976D01*
G01X1593701Y-7874D02*
G03Y0I0J3937D01*
G01Y-7874D02*
G03Y0I0J3937D01*
G01X1633071D02*
G03Y-7874I0J-3937D01*
G01D02*
X1880512D01*
G01X1633071D02*
X1880512D01*
G01X1633071Y0D02*
G03Y-7874I0J-3937D01*
G01X1693996Y829921D02*
G03X1653839I-20078J0D01*
G01X1693996D02*
G03I-20079J0D01*
G01X1653839D02*
G03X1693996I20078J0D01*
G01X1781028Y378885D02*
G03X1814839I16906J-13531D01*
G01X1781028D02*
G03X1814838I16905J-13531D01*
G01X1807913Y392016D02*
G03X1814839Y378885I37662J11473D01*
G01X1807914Y392016D02*
G03X1814838Y378885I37663J11469D01*
G01X1807913Y392016D02*
G03X1787953I-9980J-3040D01*
G01X1807914D02*
G03X1787953I-9980J-3039D01*
G01X1781028Y378885D02*
G03X1787953Y392016I-30737J24602D01*
G01X1781028Y378885D02*
G03X1787953Y392016I-30737J24602D01*
G01X1807913Y844772D02*
G03X1814839Y831641I37662J11473D01*
G01X1807914Y844772D02*
G03X1814838Y831641I37663J11469D01*
G01X1781028D02*
G03X1787953Y844772I-30737J24602D01*
G01X1781028Y831641D02*
G03X1787953Y844772I-30737J24602D01*
G01X1781028Y831641D02*
G03X1814839I16906J-13531D01*
G01X1781028D02*
G03X1814838I16905J-13531D01*
G01X1807913Y844772D02*
G03X1787953I-9980J-3040D01*
G01X1807914D02*
G03X1787953I-9980J-3039D01*
G01X1781028Y1284397D02*
G03X1814839I16906J-13531D01*
G01X1781028D02*
G03X1814838I16905J-13531D01*
G01X1807913Y1297528D02*
G03X1814839Y1284397I37661J11473D01*
G01X1807914Y1297528D02*
G03X1814838Y1284397I37663J11469D01*
G01X1807913Y1297528D02*
G03X1787953I-9980J-3040D01*
G01X1781028Y1284397D02*
G03X1787953Y1297528I-30737J24602D01*
G01X1781028Y1284397D02*
G03X1787953Y1297528I-30737J24602D01*
G01X1807914D02*
G03X1787953I-9980J-3040D01*
G01X1911220Y0D02*
G03Y-7874I0J-3937D01*
G01Y0D02*
G03Y-7874I0J-3937D01*
G01X1880512D02*
G03Y0I0J3937D01*
G01Y-7874D02*
G03Y0I0J3937D01*
G01X1930906Y1382677D02*
X1895276D01*
G01D02*
G03Y1374803I0J-3937D01*
G01X1930906Y1382677D02*
X1895276D01*
G01D02*
G03Y1374803I0J-3937D01*
G01X1864567D02*
G03Y1382677I0J3937D01*
G01Y1374803D02*
G03Y1382677I0J3937D01*
G01X1919843Y-152756D02*
G03X1934843Y-137756I0J15000D01*
G01X1919843Y-152756D02*
G03X1934843Y-137756I0J15000D01*
G01Y-11811D02*
Y-137756D01*
G01Y-11811D02*
Y-137756D01*
G01X1930906Y0D02*
G03X1934843Y3937I0J3937D01*
G01X1930906Y0D02*
G03X1934843Y3937I0J3937D01*
G01Y-11811D02*
G03X1930906Y-7874I-3937J0D01*
G01X1934843Y-11811D02*
G03X1930906Y-7874I-3937J0D01*
G01X1911220D02*
X1930906D01*
G01X1911220D02*
X1930906D01*
G01X1934843Y1370866D02*
Y3937D01*
G01D02*
Y1370866D01*
G01D02*
G03X1930906Y1374803I-3937J0D01*
G01X1934843Y1370866D02*
G03X1930906Y1374803I-3937J0D01*
G01Y1382677D02*
G03X1934843Y1386614I0J3937D01*
G01X1930906Y1382677D02*
G03X1934843Y1386614I0J3937D01*
G01D02*
Y1643268D01*
G01Y1386614D02*
Y1643268D01*
G01D02*
G03X1919843Y1658268I-15000J0D01*
G01X1934843Y1643268D02*
G03X1919843Y1658268I-15000J0D01*
G54D12*
G01X543728Y133484D02*
X563093Y137453D01*
G01X543279Y134566D02*
X563100Y138629D01*
G01X534709Y127516D02*
X543728Y133484D01*
G01X533812Y128303D02*
X543279Y134566D01*
G01X533005Y124019D02*
X534709Y127516D01*
G01X531855Y124285D02*
X533812Y128303D01*
G01X533005Y118383D02*
Y124019D01*
G01X531855Y117906D02*
Y124285D01*
G01X533293Y118095D02*
X533005Y118383D01*
G01X532816Y116945D02*
X531855Y117906D01*
G01X535439Y118095D02*
X533293D01*
G01X535473Y116945D02*
X532816D01*
G01X543279Y134566D02*
X563100Y138629D01*
G01X543728Y133484D02*
X563093Y137453D01*
G01X533812Y128303D02*
X543279Y134566D01*
G01X534709Y127516D02*
X543728Y133484D01*
G01X531855Y124285D02*
X533812Y128303D01*
G01X533005Y124019D02*
X534709Y127516D01*
G01X531855Y117906D02*
Y124285D01*
G01X533005Y118383D02*
Y124019D01*
G01X532816Y116945D02*
X531855Y117906D01*
G01X533293Y118095D02*
X533005Y118383D01*
G01X535473Y116945D02*
X532816D01*
G01X535439Y118095D02*
X533293D01*
G01X563093Y137453D02*
X625668Y123810D01*
G01X563100Y138629D02*
X625675Y124986D01*
G01X563100Y138629D02*
X625675Y124986D01*
G01X563093Y137453D02*
X625668Y123810D01*
G01D02*
X661776Y131208D01*
G01X625675Y124986D02*
X661783Y132384D01*
G01X625675Y124986D02*
X661783Y132384D01*
G01X625668Y123810D02*
X661776Y131208D01*
G01X687536Y125592D02*
X708593Y129907D01*
G01X687543Y126768D02*
X708600Y131083D01*
G01X661776Y131208D02*
X687536Y125592D01*
G01X661783Y132384D02*
X687543Y126768D01*
G01D02*
X708600Y131083D01*
G01X687536Y125592D02*
X708593Y129907D01*
G01X661783Y132384D02*
X687543Y126768D01*
G01X661776Y131208D02*
X687536Y125592D01*
G01X735413Y124060D02*
X763731Y129861D01*
G01X735420Y125236D02*
X763740Y131038D01*
G01X708593Y129907D02*
X735413Y124060D01*
G01X708600Y131083D02*
X735420Y125236D01*
G01D02*
X763740Y131038D01*
G01X735413Y124060D02*
X763731Y129861D01*
G01X708600Y131083D02*
X735420Y125236D01*
G01X708593Y129907D02*
X735413Y124060D01*
G01X789201Y124308D02*
X815304Y129655D01*
G01X789208Y125484D02*
X815311Y130831D01*
G01X763731Y129861D02*
X789201Y124308D01*
G01X763740Y131038D02*
X789208Y125484D01*
G01D02*
X815311Y130831D01*
G01X789201Y124308D02*
X815304Y129655D01*
G01X763740Y131038D02*
X789208Y125484D01*
G01X763731Y129861D02*
X789201Y124308D01*
G01X839516Y124377D02*
X868558Y118045D01*
G01X815311Y130831D02*
X868565Y119221D01*
G01X815304Y129655D02*
X839516Y124377D01*
G01X815311Y130831D02*
X868565Y119221D01*
G01X815311Y130831D02*
X868565Y119221D01*
G01X839516Y124377D02*
X868558Y118045D01*
G01X815304Y129655D02*
X839516Y124377D01*
G01X868565Y119221D02*
X927461Y131284D01*
G01X868565Y119221D02*
X927461Y131284D01*
G01X868565Y119221D02*
X927461Y131284D01*
G01X868558Y118045D02*
X914646Y127485D01*
G01X868565Y119221D02*
X927461Y131284D01*
G01X868565Y119221D02*
X927461Y131284D01*
G01X868558Y118045D02*
X914646Y127485D01*
G01X935812Y134071D02*
X949591D01*
G01X935335Y135221D02*
X949114D01*
G01X931875Y130134D02*
X935812Y134071D01*
G01X931398Y131284D02*
X935335Y135221D01*
G01X927578Y130134D02*
X931875D01*
G01X927461Y131284D02*
X931398D01*
G01X925962Y129803D02*
X927578Y130134D01*
G01X921651Y128920D02*
X923267Y129251D01*
G01X917341Y128037D02*
X918957Y128368D01*
G01X935335Y135221D02*
X949114D01*
G01X935812Y134071D02*
X949591D01*
G01X931398Y131284D02*
X935335Y135221D01*
G01X931875Y130134D02*
X935812Y134071D01*
G01X927461Y131284D02*
X931398D01*
G01X927578Y130134D02*
X931875D01*
G01X925962Y129803D02*
X927578Y130134D01*
G01X921651Y128920D02*
X923267Y129251D01*
G01X917341Y128037D02*
X918957Y128368D01*
G01X952112Y139583D02*
X951745Y140317D01*
G01X950962Y139311D02*
X950716Y139803D01*
G01X952112Y136592D02*
Y139583D01*
G01X950962Y137069D02*
Y139311D01*
G01X949591Y134071D02*
X952112Y136592D01*
G01X949114Y135221D02*
X950962Y137069D01*
G01Y139311D02*
X950716Y139803D01*
G01X952112Y139583D02*
X951745Y140317D01*
G01X950962Y137069D02*
Y139311D01*
G01X952112Y136592D02*
Y139583D01*
G01X949114Y135221D02*
X950962Y137069D01*
G01X949591Y134071D02*
X952112Y136592D01*
M02*
